G04 ================== begin FILE IDENTIFICATION RECORD ==================*
G04 Layout Name:  12004-1.brd*
G04 Film Name:    DIF_REF_BOTTOM*
G04 File Format:  Gerber RS274X*
G04 File Origin:  Cadence Allegro 16.2-S033*
G04 Origin Date:  Tue Oct 16 14:36:13 2012*
G04 *
G04 Layer:  BOARD GEOMETRY/OUTLINE*
G04 Layer:  BOARD GEOMETRY/DIF_REF_BOTTOM*
G04 Layer:  BOARD GEOMETRY/PANEL_OUTLINE*
G04 *
G04 Offset:    (0.00 0.00)*
G04 Mirror:    No*
G04 Mode:      Positive*
G04 Rotation:  0*
G04 FullContactRelief:  No*
G04 UndefLineWidth:     6.00*
G04 ================== end FILE IDENTIFICATION RECORD ====================*
%FSLAX35Y35*MOIN*%
%IR0*IPPOS*OFA0.00000B0.00000*MIA0B0*SFA1.00000B1.00000*%
%ADD10C,.004*%
%ADD11C,.006*%
G75*
%LPD*%
G75*
G54D10*
G01X76200Y557885D02*
X82179Y551906D01*
G01X42500Y556771D02*
G03X43964Y553236I5000J0D01*
G01D02*
X44314Y552886D01*
G01D02*
G03X47849Y551422I3535J3536D01*
G01D02*
X73735D01*
G01D02*
G02X77630Y549810I1J-5509D01*
G01D02*
G02X79243Y545913I-3898J-3896D01*
G01X41200Y556771D02*
G03X43044Y552316I6300J-1D01*
G01D02*
X43394Y551966D01*
G01D02*
G03X47849Y550122I4454J4456D01*
G01D02*
X73736D01*
G01D02*
G02X76710Y548890I-1J-4208D01*
G01D02*
G02X77942Y545913I-2978J-2976D01*
G01D02*
X77943Y545914D01*
G01D02*
Y517128D01*
G01D02*
G03X79407Y513593I5000J0D01*
G01X65550Y605972D02*
X66206Y606628D01*
G01D02*
G02X69569Y608021I3363J-3363D01*
G01X65550Y609872D02*
X67122D01*
G01D02*
G02X67800Y609591I0J-959D01*
G01D02*
G03X68803Y609798I344J866D01*
G01D02*
X68841Y609836D01*
G01D02*
G03X69496Y611417I-1581J1581D01*
G01X65650Y596372D02*
X67029D01*
G01D02*
G03X67591Y596934I0J562D01*
G01D02*
Y598626D01*
G01D02*
G02X68241Y599276I650J0D01*
G01D02*
X69009D01*
G01D02*
G02X69569Y598716I0J-560D01*
G01D02*
Y598159D01*
G01X65650Y600272D02*
X66569D01*
G01D02*
G03X69599Y601527I0J4285D01*
G01X65650Y572987D02*
X66615Y573953D01*
G01D02*
G02X67423Y574287I807J-808D01*
G01D02*
X67723D01*
G01D02*
G02X69260Y573651I1J-2173D01*
G01D02*
X69450Y573460D01*
G01X65650Y576887D02*
X66615Y575921D01*
G01D02*
G03X67423Y575587I807J808D01*
G01D02*
X67723D01*
G01D02*
G03X68733Y576006I-1J1429D01*
G01D02*
X69388Y576660D01*
G01X65750Y563487D02*
Y563535D01*
G01D02*
G02X66114Y564414I1243J0D01*
G01D02*
X67071Y565371D01*
G01D02*
G02X67778Y565664I707J-706D01*
G01D02*
X68898D01*
G01D02*
G02X69555Y565007I0J-657D01*
G01D02*
Y564187D01*
G01X65750Y567387D02*
X69523D01*
G01X62050Y605972D02*
X57160D01*
G01D02*
G02X53567Y609565I0J3593D01*
G01D02*
Y610525D01*
G01D02*
X53568D01*
G01D02*
G02X54810Y613522I4231J2D01*
G01D02*
X54868Y613579D01*
G01D02*
X58113Y616824D01*
G01D02*
G02X64231Y619358I6119J-6120D01*
G01D02*
X78869D01*
G01X62050Y609872D02*
X60119Y607941D01*
G01D02*
X59735Y607558D01*
G01D02*
G02X59046Y607272I-690J689D01*
G01D02*
X57160D01*
G01D02*
G02X54867Y609565I0J2293D01*
G01D02*
Y610525D01*
G01D02*
G02X55725Y612598I2931J1D01*
G01D02*
X55779Y612651D01*
G01D02*
X59032Y615904D01*
G01D02*
G02X64232Y618058I5200J-5200D01*
G01D02*
X78869D01*
G01X62150Y596372D02*
X60902D01*
G01D02*
G02X59970Y597304I0J932D01*
G01D02*
Y598244D01*
G01D02*
G03X59242Y598972I-728J0D01*
G01D02*
X57338D01*
G01D02*
G03X54691Y596325I0J-2647D01*
G01D02*
Y591506D01*
G01D02*
G03X59511Y586686I4820J0D01*
G01D02*
X70057D01*
G01D02*
G02X74229Y584958I1J-5899D01*
G01D02*
X75932Y583255D01*
G01D02*
X75934D01*
G01D02*
X76315Y582874D01*
G01D02*
X76927Y582260D01*
G01D02*
G02X78292Y578964I-3295J-3295D01*
G01X62150Y600272D02*
X57338D01*
G01D02*
G03X53391Y596325I0J-3947D01*
G01D02*
Y591506D01*
G01D02*
G03X59511Y585386I6120J0D01*
G01D02*
X70057D01*
G01D02*
G02X73309Y584039I0J-4599D01*
G01D02*
X75393Y581955D01*
G01D02*
X75394D01*
G01D02*
X76008Y581340D01*
G01D02*
G02X76992Y578964I-2376J-2376D01*
G01D02*
Y577131D01*
G01D02*
G03X80437Y568811I11766J-2D01*
G01X62150Y572987D02*
X56872D01*
G01D02*
G02X53033Y576826I0J3839D01*
G01D02*
Y578196D01*
G01D02*
G02X57823Y582986I4790J0D01*
G01D02*
X69541D01*
G01D02*
G02X71975Y581978I1J-3441D01*
G01D02*
X72485Y581468D01*
G01D02*
G02X73843Y578189I-3281J-3280D01*
G01D02*
Y566715D01*
G01D02*
G03X77120Y558804I11188J0D01*
G01D02*
X83099Y552826D01*
G01X62150Y576887D02*
X59927Y574665D01*
G01D02*
G02X59016Y574287I-912J911D01*
G01D02*
X56872D01*
G01D02*
G02X54333Y576826I0J2539D01*
G01D02*
Y578196D01*
G01D02*
G02X57823Y581686I3490J0D01*
G01D02*
X69541D01*
G01D02*
G02X71055Y581059I0J-2141D01*
G01D02*
X71565Y580549D01*
G01D02*
G02X72543Y578188I-2361J-2361D01*
G01D02*
Y566714D01*
G01D02*
G03X76200Y557885I12488J1D01*
G01X62250Y563487D02*
X61381D01*
G01D02*
G02X60582Y563818I0J1130D01*
G01D02*
G02X60251Y564617I799J799D01*
G01D02*
Y565239D01*
G01D02*
G03X59403Y566087I-848J0D01*
G01D02*
X57600D01*
G01D02*
X57160Y565647D01*
G01D02*
X55960D01*
G01D02*
X55520Y566087D01*
G01D02*
X54320D01*
G01D02*
X53880Y565647D01*
G01D02*
X52680D01*
G01D02*
X52240Y566087D01*
G01D02*
X51040D01*
G01D02*
X50600Y565647D01*
G01D02*
X49400D01*
G01D02*
X48960Y566087D01*
G01D02*
X47500D01*
G01D02*
G03X42500Y561087I0J-5000D01*
G01D02*
Y556771D01*
G01X62250Y567387D02*
X47500D01*
G01D02*
G03X41200Y561087I0J-6300D01*
G01D02*
Y556771D01*
G01X66201Y690503D02*
X68244D01*
G01D02*
G03X69451Y691003I0J1707D01*
G01X66201Y694403D02*
X67843Y692761D01*
G01D02*
G03X68803I480J480D01*
G01D02*
G03X69474Y694381I-1620J1620D01*
G01D02*
Y694403D01*
G01X66201Y680803D02*
X67166Y681769D01*
G01D02*
G02X67974Y682103I807J-808D01*
G01D02*
X68082D01*
G01D02*
G02X68712Y681842I0J-891D01*
G01D02*
X69451Y681103D01*
G01X66201Y684703D02*
X68485D01*
G01D02*
G02X69451Y684303I0J-1366D01*
G01X72532Y702368D02*
X82168Y692732D01*
G01X62701Y690503D02*
X62087Y691117D01*
G01D02*
G03X60431Y691803I-1656J-1656D01*
G01D02*
X57589D01*
G01D02*
G02X53851Y695541I0J3738D01*
G01D02*
Y696744D01*
G01D02*
G02X55000Y699518I3923J0D01*
G01X71848Y699510D02*
X84637Y686722D01*
G01X62701Y694403D02*
X62144Y693845D01*
G01D02*
G02X60351Y693103I-1792J1793D01*
G01D02*
X57589D01*
G01D02*
G02X55151Y695541I0J2438D01*
G01D02*
Y696744D01*
G01D02*
G02X55920Y698598I2623J-1D01*
G01X70928Y698590D02*
X83717Y685802D01*
G01X62701Y680803D02*
X61087D01*
G01D02*
G02X60499Y681391I0J588D01*
G01D02*
Y682647D01*
G01D02*
G03X59743Y683403I-756J0D01*
G01D02*
X54815D01*
G01D02*
G03X51349Y681968I-1J-4901D01*
G01D02*
X51314Y681932D01*
G01D02*
X49952Y680570D01*
G01D02*
G03X48440Y676920I3650J-3650D01*
G01D02*
Y675053D01*
G01D02*
G03X54503Y668990I6063J0D01*
G01D02*
X57839D01*
G01D02*
G02X61374Y667526I0J-5000D01*
G01D02*
X75102Y653798D01*
G01D02*
X75724D01*
G01D02*
X76573Y652949D01*
G01D02*
Y652327D01*
G01D02*
X77421Y651479D01*
G01D02*
X78044D01*
G01D02*
X78892Y650630D01*
G01X62701Y684703D02*
X54815D01*
G01D02*
Y684702D01*
G01D02*
G03X50422Y682881I-3J-6201D01*
G01D02*
X50382Y682839D01*
G01D02*
X49032Y681490D01*
G01D02*
G03X47140Y676920I4570J-4569D01*
G01D02*
Y675053D01*
G01D02*
G03X54503Y667690I7363J0D01*
G01D02*
X57839D01*
G01D02*
G02X60454Y666606I-1J-3699D01*
G01D02*
X101538Y625522D01*
G01X65150Y724613D02*
X65753D01*
G01D02*
G03X69548Y726185I0J5367D01*
G01X65150Y728513D02*
X66634D01*
G01D02*
G02X67218Y728271I0J-826D01*
G01D02*
X67236Y728253D01*
G01D02*
G03X68103Y727894I867J867D01*
G01D02*
X68947D01*
G01D02*
G03X69472Y728419I0J525D01*
G01D02*
Y729385D01*
G01X65250Y714713D02*
X66145Y715608D01*
G01D02*
G02X67123Y716013I978J-978D01*
G01D02*
X68023D01*
G01D02*
G02X69048Y715589I1J-1449D01*
G01D02*
X69523Y715113D01*
G01X65250Y718613D02*
X66145Y717718D01*
G01D02*
G03X67123Y717313I978J978D01*
G01D02*
X68023D01*
G01D02*
G03X68876Y717667I-1J1207D01*
G01D02*
X69523Y718313D01*
G01X61650Y724613D02*
X57589D01*
G01D02*
G02X54117Y728085I0J3472D01*
G01D02*
Y729788D01*
G01D02*
G02X55125Y732224I3444J1D01*
G01D02*
X57832Y734931D01*
G01D02*
G02X61934Y736629I4101J-4103D01*
G01D02*
X82332D01*
G01X61650Y728513D02*
X59728Y726591D01*
G01D02*
X59511Y726373D01*
G01D02*
G02X58399Y725913I-1111J1112D01*
G01D02*
X57589D01*
G01D02*
G02X55417Y728085I0J2172D01*
G01D02*
Y729788D01*
G01D02*
G02X56045Y731304I2144J0D01*
G01D02*
X58752Y734011D01*
G01D02*
G02X61934Y735329I3182J-3182D01*
G01D02*
X82332D01*
G01X61750Y714713D02*
X61435Y715027D01*
G01D02*
G03X59126Y715984I-2309J-2307D01*
G01D02*
X57303D01*
G01D02*
G03X53077Y711758I0J-4226D01*
G01D02*
Y710158D01*
G01D02*
G03X54395Y706976I4500J0D01*
G01D02*
X55653Y705718D01*
G01D02*
G03X58835Y704400I3182J3182D01*
G01D02*
X70764D01*
G01D02*
G02X73452Y703288I1J-3802D01*
G01D02*
X74241Y702499D01*
G01D02*
X74864D01*
G01D02*
X75712Y701650D01*
G01D02*
Y701028D01*
G01D02*
X76561Y700179D01*
G01D02*
X77183D01*
G01D02*
X78031Y699331D01*
G01D02*
Y698709D01*
G01D02*
X78880Y697860D01*
G01X61750Y718613D02*
X61336Y718200D01*
G01D02*
G02X59126Y717284I-2211J2210D01*
G01D02*
X57303D01*
G01D02*
G03X51777Y711758I0J-5526D01*
G01D02*
Y710158D01*
G01D02*
G03X53475Y706056I5801J-1D01*
G01D02*
X54733Y704798D01*
G01D02*
G03X58835Y703100I4101J4103D01*
G01D02*
X70764D01*
G01D02*
G02X72532Y702368I0J-2501D01*
G01X55000Y699518D02*
G02X57774Y700667I2774J-2774D01*
G01D02*
X69621D01*
G01D02*
G02X70254Y700541I0J-1653D01*
G01D02*
X70388Y700486D01*
G01D02*
G02X71848Y699510I-1723J-4157D01*
G01X55920Y698598D02*
G02X57774Y699367I1855J-1854D01*
G01D02*
X69621D01*
G01D02*
G02X69756Y699340I0J-353D01*
G01D02*
X69758Y699339D01*
G01D02*
X69892Y699284D01*
G01D02*
G02X70928Y698590I-1228J-2954D01*
G01X149443Y317105D02*
G02X146518Y318316I-1J4136D01*
G01D02*
X146517Y318318D01*
G01D02*
X106247Y358588D01*
G01X149442Y315805D02*
G02X145598Y317397I1J5438D01*
G01D02*
X105327Y357668D01*
G01X107531Y369068D02*
X151508Y325091D01*
G01X106611Y368148D02*
X150588Y324171D01*
G01X111231Y371419D02*
X147725Y334925D01*
G01D02*
X148051Y334598D01*
G01D02*
G03X159701Y329773I11649J11650D01*
G01X119607Y361203D02*
X146805Y334006D01*
G01D02*
X147131Y333679D01*
G01D02*
G03X159701Y328473I12569J12569D01*
G01X143667Y346053D02*
G03X162691Y338173I19024J19025D01*
G01X118762Y369120D02*
X142748Y345134D01*
G01D02*
G03X162692Y336873I19944J19944D01*
G01X133864Y398350D02*
G02X133310Y397012I-1893J0D01*
G01D02*
X132783Y396485D01*
G01D02*
G03X132264Y395232I1253J-1253D01*
G01D02*
X132263Y395233D01*
G01D02*
Y395005D01*
G01D02*
X132264D01*
G01D02*
Y394025D01*
G01D02*
X132263Y393951D01*
G01D02*
Y391905D01*
G01D02*
G03X137399Y379504I17537J-1D01*
G01D02*
X140099Y376805D01*
G01D02*
X150317Y366587D01*
G01X133864Y402287D02*
X133405Y401828D01*
G01D02*
G03X131863Y398105I3723J-3723D01*
G01D02*
Y397779D01*
G01D02*
G02X131564Y397057I-1021J0D01*
G01D02*
G03X130963Y395232I2472J-1825D01*
G01D02*
Y391905D01*
G01D02*
X130964D01*
G01D02*
G03X136479Y378584I18837J-3D01*
G01D02*
X139179Y375885D01*
G01D02*
X149397Y365667D01*
G01X137801Y398350D02*
G03X136964Y396329I2021J-2021D01*
G01D02*
Y387568D01*
G01D02*
G03X137902Y385303I3203J0D01*
G01D02*
X144174Y379031D01*
G01D02*
X148719Y374485D01*
G01X148721D02*
X150940Y372266D01*
G01X137801Y402287D02*
G03X135664Y397128I5159J-5159D01*
G01D02*
Y387568D01*
G01D02*
G03X136982Y384383I4504J-2D01*
G01D02*
X138958Y382408D01*
G01D02*
X147800Y373565D01*
G01D02*
X148180Y373185D01*
G01D02*
X148182D01*
G01D02*
X150020Y371346D01*
G01X106247Y358588D02*
G02X100463Y372550I13960J13962D01*
G01D02*
Y393312D01*
G01D02*
G02X100742Y394860I3943J89D01*
G01D02*
G02X100873Y395099I2555J-1245D01*
G01D02*
G03X102364Y398350I-12810J7842D01*
G01X105327Y357668D02*
G02X99163Y372549I14881J14881D01*
G01D02*
Y393400D01*
G01D02*
X99162D01*
G01D02*
Y393401D01*
G01D02*
G02X99551Y395383I5244J0D01*
G01D02*
G02X100014Y396144I3750J-1760D01*
G01D02*
G03X100576Y397800I-2159J1656D01*
G01D02*
G02X101000Y399500I3620J0D01*
G01D02*
X101358Y399858D01*
G01D02*
G03X102364Y402287I-2429J2429D01*
G01X106301Y398350D02*
G03X106213Y398138I211J-212D01*
G01D02*
Y372250D01*
G01D02*
G03X107531Y369068I4500J0D01*
G01X106301Y402287D02*
X105838Y401824D01*
G01D02*
G03X104600Y398834I2990J-2989D01*
G01D02*
Y397477D01*
G01D02*
G03X104763Y397083I557J0D01*
G01D02*
G02X104913Y396721I-362J-362D01*
G01D02*
Y372250D01*
G01D02*
G03X106611Y368148I5801J-1D01*
G01X152881Y380412D02*
X145679Y387614D01*
G01D02*
G02X145005Y389241I1627J1627D01*
G01D02*
Y396274D01*
G01D02*
G02X145120Y397090I2936J2D01*
G01D02*
G02X145865Y398350I2820J-817D01*
G01X152926Y378527D02*
X144759Y386694D01*
G01D02*
G02X143705Y389240I2548J2546D01*
G01D02*
Y397500D01*
G01D02*
G02X145563Y401984I6342J-1D01*
G01D02*
X145865Y402287D01*
G01X149014Y397009D02*
X148485Y396480D01*
G01D02*
G03X147732Y394662I1819J-1818D01*
G01D02*
X147731Y394663D01*
G01D02*
Y394381D01*
G01D02*
G03Y394356I1813J-13D01*
G01D02*
Y390752D01*
G01D02*
G03X148411Y389111I2322J1D01*
G01D02*
X152791Y384731D01*
G01X148831Y401458D02*
G03X147565Y398400I3058J-3057D01*
G01D02*
Y398004D01*
G01D02*
G02X147052Y396766I-1751J0D01*
G01D02*
G03X146431Y394662I3251J-2103D01*
G01D02*
Y390753D01*
G01D02*
G03X147491Y388191I3623J-1D01*
G01D02*
X151871Y383811D01*
G01X110238Y398350D02*
X110099Y398210D01*
G01D02*
G03X109463Y396676I1534J-1535D01*
G01D02*
G02X108916Y395355I-1870J1D01*
G01D02*
G03X108638Y394683I673J-672D01*
G01D02*
Y393509D01*
G01D02*
G03X109063Y392483I1451J0D01*
G01D02*
G02X109913Y390431I-2052J-2052D01*
G01D02*
Y374601D01*
G01D02*
G03X111231Y371419I4500J0D01*
G01X110238Y402287D02*
X109951Y402001D01*
G01D02*
G03X108163Y397683I4318J-4317D01*
G01D02*
Y396677D01*
G01D02*
G02X107996Y396274I-570J0D01*
G01D02*
G03X107338Y394682I1593J-1590D01*
G01D02*
Y393508D01*
G01D02*
G03X108142Y391565I2751J1D01*
G01D02*
X108143D01*
G01D02*
X108144Y391564D01*
G01D02*
G02X108613Y390430I-1133J-1133D01*
G01D02*
Y374601D01*
G01D02*
G03X110311Y370499I5801J-1D01*
G01D02*
X119607Y361203D01*
G01X114175Y398350D02*
G03X113645Y397070I1280J-1280D01*
G01D02*
Y384615D01*
G01D02*
G03X119682Y370040I20612J0D01*
G01D02*
X143668Y346054D01*
G01D02*
X143667Y346053D01*
G01X114175Y402287D02*
G03X112345Y397869I4418J-4418D01*
G01D02*
Y384615D01*
G01D02*
G03X118762Y369120I21913J-2D01*
G01X122053Y398350D02*
G03X121446Y397393I1823J-1828D01*
G01D02*
G02X120896Y396065I-1878J0D01*
G01D02*
G03X120219Y394693I1683J-1683D01*
G01D02*
X120203Y394681D01*
G01D02*
X120124Y394095D01*
G01D02*
G03X120109Y393868I1688J-226D01*
G01D02*
Y387871D01*
G01D02*
G03X128348Y367980I28130J0D01*
G01D02*
X143260Y353068D01*
G01D02*
X143906Y352421D01*
G01D02*
G03X162853Y344573I18947J18947D01*
G01X122053Y402287D02*
G03X120021Y397903I4964J-4964D01*
G01D02*
G02X119678Y396749I-2110J-1D01*
G01D02*
G03X118899Y394868I1881J-1881D01*
G01D02*
X118913Y394851D01*
G01D02*
X118835Y394268D01*
G01D02*
G03X118809Y393868I2977J-394D01*
G01D02*
Y387871D01*
G01D02*
G03X127429Y367060I29430J-1D01*
G01D02*
X127428D01*
G01D02*
X142340Y352149D01*
G01D02*
X142986Y351502D01*
G01D02*
G03X162854Y343273I19866J19866D01*
G01X125990Y398350D02*
G02X125750Y397769I-821J-1D01*
G01D02*
X124663Y396683D01*
G01D02*
X124550Y396571D01*
G01D02*
G03X124100Y395483I1088J-1087D01*
G01D02*
Y391605D01*
G01D02*
G03X132586Y371118I28973J0D01*
G01D02*
X133299Y370405D01*
G01D02*
X145051Y358652D01*
G01D02*
G03X160628Y352200I15577J15577D01*
G01X125990Y402287D02*
X125025Y401321D01*
G01D02*
G03X124263Y399483I1838J-1839D01*
G01D02*
Y398983D01*
G01D02*
G02X123656Y397516I-2074J-1D01*
G01D02*
X123632Y397493D01*
G01D02*
G03X122801Y395483I2007J-2007D01*
G01D02*
X122800D01*
G01D02*
Y391605D01*
G01D02*
G03X131666Y370198I30274J-1D01*
G01D02*
X144131Y357733D01*
G01D02*
G03X160628Y350900I16496J16496D01*
G01X129927Y398350D02*
G03X129407Y397095I1255J-1255D01*
G01D02*
Y383878D01*
G01D02*
G03X130725Y380696I4500J0D01*
G01D02*
X150356Y361065D01*
G01X129927Y402287D02*
X129298Y401658D01*
G01D02*
G03X128107Y398783I2875J-2875D01*
G01D02*
Y383878D01*
G01D02*
G03X129805Y379776I5801J-1D01*
G01D02*
X149436Y360145D01*
G01X141738Y398350D02*
G02X141369Y397459I-1260J0D01*
G01D02*
X140336Y396426D01*
G01D02*
G03X139800Y395132I1294J-1294D01*
G01D02*
Y390764D01*
G01D02*
G03X141118Y387582I4500J0D01*
G01D02*
X152662Y376038D01*
G01X141738Y402287D02*
X141140Y401689D01*
G01D02*
G03X139783Y398413I3276J-3276D01*
G01D02*
G02X139366Y397303I-2411J272D01*
G01D02*
G02X139342Y397269I-1984J1375D01*
G01D02*
G03X138500Y395133I2288J-2136D01*
G01D02*
Y390764D01*
G01D02*
G03X140198Y386662I5801J-1D01*
G01D02*
X151742Y375118D01*
G01X141149Y486063D02*
Y486015D01*
G01D02*
G03X141738Y484968I2163J527D01*
G01X139786Y486214D02*
Y485214D01*
G01D02*
G03X141364Y481406I5386J1D01*
G01D02*
X141738Y481031D01*
G01X137084Y486094D02*
G03X137373Y485396I987J0D01*
G01D02*
X137801Y484968D01*
G01X135784Y526853D02*
Y484714D01*
G01D02*
G03X136962Y481870I4022J0D01*
G01D02*
X137801Y481031D01*
G01X132413Y487272D02*
G02X133167Y485877I-1969J-1966D01*
G01D02*
G03X133317Y485515I512J0D01*
G01D02*
X133864Y484968D01*
G01X131493Y486352D02*
G02X131895Y485609I-1048J-1047D01*
G01D02*
G02X131927Y485304I-1450J-306D01*
G01D02*
G03X133579Y481316I5640J0D01*
G01D02*
X133864Y481031D01*
G01X129527Y516643D02*
Y485934D01*
G01D02*
G03X129927Y484968I1366J0D01*
G01X128227Y516642D02*
Y484377D01*
G01D02*
G03X129391Y481567I3974J0D01*
G01D02*
X129927Y481031D01*
G01X146612Y486918D02*
G02X145896Y485188I-2446J-1D01*
G01D02*
X145675Y484968D01*
G01X147912Y507250D02*
Y485595D01*
G01D02*
G02X147375Y484299I-1833J0D01*
G01D02*
Y484263D01*
G01D02*
X146758Y483647D01*
G01D02*
G03X145675Y481031I2616J-2615D01*
G01X125052Y486309D02*
G03X125337Y485621I973J0D01*
G01D02*
X125990Y484968D01*
G01X123753Y486249D02*
G03X125861Y481160I7197J0D01*
G01D02*
X125990Y481031D01*
G01X121461Y486397D02*
G03X122053Y484968I2021J0D01*
G01X120161Y509305D02*
Y484971D01*
G01D02*
G03X121609Y481475I4944J0D01*
G01D02*
X122053Y481031D01*
G01X114743Y486110D02*
X114581Y485948D01*
G01D02*
G03X114175Y484968I980J-980D01*
G01X113823Y487030D02*
X112831Y486038D01*
G01D02*
G03X112475Y485179I859J-859D01*
G01D02*
Y484824D01*
G01D02*
G03X113955Y481251I5053J0D01*
G01D02*
X114175Y481031D01*
G01X112577Y486999D02*
X110764Y485186D01*
G01D02*
G02X110238Y484968I-526J526D01*
G01X109735Y486875D02*
X108752Y485892D01*
G01D02*
G03X108438Y485134I758J-758D01*
G01D02*
Y484348D01*
G01D02*
G03X109511Y481759I3662J1D01*
G01D02*
X110238Y481031D01*
G01X107691Y486962D02*
X106728Y485999D01*
G01D02*
G03X106301Y484968I1031J-1031D01*
G01X106771Y487882D02*
X104850Y485961D01*
G01D02*
G03X104570Y485285I676J-676D01*
G01D02*
Y484118D01*
G01D02*
G03X105529Y481803I3274J0D01*
G01D02*
X106301Y481031D01*
G01X104148Y486582D02*
X102654Y485088D01*
G01D02*
G02X102364Y484968I-290J290D01*
G01X101433Y486485D02*
X100944Y485996D01*
G01D02*
G03X100651Y485289I707J-707D01*
G01D02*
Y484413D01*
G01D02*
G03X101831Y481564I4029J0D01*
G01D02*
X102364Y481031D01*
G01X99489Y487532D02*
G02X98427Y484968I-3626J0D01*
G01X97185Y486238D02*
G03X96485Y484548I1690J-1690D01*
G01D02*
G03X97599Y481860I3802J1D01*
G01D02*
X98427Y481031D01*
G01X95750Y486228D02*
X94490Y484968D01*
G01X93189Y486301D02*
X92802Y485699D01*
G01D02*
Y485685D01*
G01D02*
X92790Y485673D01*
G01D02*
Y484909D01*
G01D02*
G03X93330Y483606I1843J0D01*
G01D02*
X93475Y483461D01*
G01D02*
G03X93763Y483269I626J627D01*
G01D02*
X93926Y483201D01*
G01D02*
X93954Y483173D01*
G01D02*
G02X94490Y481879I-1294J-1294D01*
G01D02*
Y481031D01*
G01X141350Y728945D02*
Y532889D01*
G01D02*
X141351Y532890D01*
G01D02*
G03X142512Y530086I3967J0D01*
G01D02*
G02X144595Y525057I-5029J-5029D01*
G01D02*
Y518612D01*
G01D02*
G02X142493Y513433I-7432J0D01*
G01D02*
X142494Y513432D01*
G01D02*
G03X140784Y508134I7357J-5300D01*
G01D02*
Y491384D01*
G01D02*
G02X140145Y489644I-2687J-1D01*
G01D02*
G03X140121Y489589I992J-465D01*
G01D02*
X140082Y489492D01*
G01D02*
G03X140423Y487816I1437J-580D01*
G01D02*
G02X141149Y486063I-1753J-1753D01*
G01X140050Y728945D02*
Y532890D01*
G01D02*
G03X141592Y529166I5268J0D01*
G01D02*
G02X142342Y528245I-4108J-4111D01*
G01D02*
G02X143294Y525057I-4860J-3187D01*
G01D02*
X143295Y525058D01*
G01D02*
Y518612D01*
G01D02*
G02X141499Y514276I-6132J0D01*
G01D02*
G03X139484Y508135I8353J-6142D01*
G01D02*
Y491385D01*
G01D02*
G02X139078Y490405I-1386J0D01*
G01D02*
G03X138738Y489174I2056J-1230D01*
G01D02*
Y488744D01*
G01D02*
G03X139503Y486896I2615J0D01*
G01D02*
X139504Y486895D01*
G01D02*
G02X139786Y486214I-681J-681D01*
G01X135598Y730929D02*
Y530441D01*
G01D02*
G03X136234Y528906I2171J0D01*
G01D02*
G02X137084Y526854I-2052J-2052D01*
G01D02*
Y486094D01*
G01X134298Y730929D02*
Y530440D01*
G01D02*
G03X135314Y527986I3472J0D01*
G01D02*
G02X135617Y527565I-1132J-1134D01*
G01D02*
G02X135784Y526853I-1435J-712D01*
G01X130544Y734328D02*
Y531071D01*
G01D02*
G03X131793Y528056I4264J0D01*
G01D02*
G02X133227Y524594I-3462J-3462D01*
G01D02*
Y491762D01*
G01D02*
G02X132459Y489905I-2626J-1D01*
G01D02*
X132458D01*
G01D02*
G03X132344Y489768I712J-708D01*
G01D02*
G03X132164Y489191I835J-577D01*
G01D02*
Y487870D01*
G01D02*
X132165Y487871D01*
G01D02*
G03X132413Y487272I847J0D01*
G01X129244Y734328D02*
Y531070D01*
G01D02*
G03X130873Y527136I5565J0D01*
G01D02*
G02X131552Y526192I-2541J-2544D01*
G01D02*
G02X131927Y524594I-3221J-1599D01*
G01D02*
Y491762D01*
G01D02*
G02X131539Y490825I-1325J0D01*
G01D02*
X131538Y490824D01*
G01D02*
G03X130864Y489193I1631J-1629D01*
G01D02*
Y487871D01*
G01D02*
G03X131493Y486352I2148J0D01*
G01X126783Y736400D02*
Y523267D01*
G01D02*
G03X127587Y521328I2742J1D01*
G01D02*
G02X128837Y519587I-4687J-4684D01*
G01D02*
G02X129527Y516643I-5936J-2944D01*
G01X125483Y801701D02*
Y523266D01*
G01D02*
G03X126667Y520408I4042J0D01*
G01D02*
G02X127672Y519009I-3766J-3766D01*
G01D02*
G02X128227Y516642I-4771J-2367D01*
G01X151215Y518365D02*
G03X146612Y507250I11115J-11114D01*
G01D02*
Y486918D01*
G01X152135Y517445D02*
G03X147912Y507250I10195J-10195D01*
G01X122316Y696645D02*
Y522149D01*
G01D02*
X122317Y522150D01*
G01D02*
G03X124195Y517454I6805J-2D01*
G01D02*
G02X125161Y515122I-2332J-2332D01*
G01D02*
Y491343D01*
G01D02*
G02X124553Y489874I-2079J0D01*
G01D02*
X124552Y489873D01*
G01D02*
G03X124290Y489239I634J-633D01*
G01D02*
Y488403D01*
G01D02*
G03Y488379I1058J-12D01*
G01D02*
X124291D01*
G01D02*
G03X124442Y487858I1057J24D01*
G01D02*
G02X124533Y487758I-1558J-1509D01*
G01D02*
G02X125048Y486413I-1654J-1404D01*
G01D02*
G02X125052Y486309I-2406J-145D01*
G01X121016Y696645D02*
Y522150D01*
G01D02*
G03X123389Y516417I8105J-3D01*
G01D02*
G02X123860Y515280I-1137J-1137D01*
G01D02*
X123861Y515281D01*
G01D02*
Y491344D01*
G01D02*
G02X123860Y491343I-550J549D01*
G01D02*
G02X123633Y490794I-778J0D01*
G01D02*
G03X122990Y489239I1554J-1553D01*
G01D02*
Y488402D01*
G01D02*
G03X123428Y487034I2358J1D01*
G01D02*
X123493Y486968D01*
G01D02*
G02X123748Y486354I-614J-615D01*
G01D02*
G02X123752Y486276I-1105J-96D01*
G01D02*
G02Y486261I-1108J-7D01*
G01D02*
G02X123753Y486249I-1103J-98D01*
G01X116486Y593300D02*
Y543300D01*
G01D02*
X116926Y542860D01*
G01D02*
Y541660D01*
G01D02*
X116486Y541220D01*
G01D02*
Y540020D01*
G01D02*
X116926Y539580D01*
G01D02*
Y538380D01*
G01D02*
X116486Y537940D01*
G01D02*
Y536740D01*
G01D02*
X116926Y536300D01*
G01D02*
Y535100D01*
G01D02*
X116486Y534660D01*
G01D02*
Y533460D01*
G01D02*
X116926Y533020D01*
G01D02*
Y531820D01*
G01D02*
X116486Y531380D01*
G01D02*
Y530180D01*
G01D02*
X116926Y529740D01*
G01D02*
Y528540D01*
G01D02*
X116486Y528100D01*
G01D02*
Y521144D01*
G01D02*
X116487Y521145D01*
G01D02*
G03X119073Y514898I8833J-2D01*
G01D02*
X119195Y514777D01*
G01D02*
G02X121461Y509305I-5472J-5471D01*
G01D02*
Y486397D01*
G01X115186Y672747D02*
Y521145D01*
G01D02*
G03X118155Y513976I10133J-3D01*
G01D02*
X118277Y513855D01*
G01D02*
G02X120162Y509305I-4553J-4552D01*
G01D02*
X120161D01*
G01X112157Y666480D02*
Y518247D01*
G01D02*
X112158Y518248D01*
G01D02*
G03X114112Y513527I6675J-2D01*
G01D02*
G02X115240Y511958I-4226J-4228D01*
G01D02*
G02X115863Y509300I-5355J-2657D01*
G01D02*
Y488817D01*
G01D02*
G02X114743Y486110I-3828J-2D01*
G01X110857Y666480D02*
Y518248D01*
G01D02*
G03X113192Y512607I7976J-2D01*
G01D02*
G02X114075Y511379I-3306J-3309D01*
G01D02*
G02X114563Y509299I-4190J-2080D01*
G01D02*
Y488817D01*
G01D02*
G02X113823Y487030I-2527J0D01*
G01X103922Y592400D02*
Y542400D01*
G01D02*
X104362Y541960D01*
G01D02*
Y540760D01*
G01D02*
X103922Y540320D01*
G01D02*
Y539120D01*
G01D02*
X104362Y538680D01*
G01D02*
Y537480D01*
G01D02*
X103922Y537040D01*
G01D02*
Y535840D01*
G01D02*
X104362Y535400D01*
G01D02*
Y534200D01*
G01D02*
X103922Y533760D01*
G01D02*
Y532560D01*
G01D02*
X104362Y532120D01*
G01D02*
Y530920D01*
G01D02*
X103922Y530480D01*
G01D02*
Y529280D01*
G01D02*
X104362Y528840D01*
G01D02*
Y527640D01*
G01D02*
X103922Y527200D01*
G01D02*
Y516459D01*
G01D02*
G03X105991Y511464I7064J0D01*
G01D02*
X107730Y509725D01*
G01D02*
Y509724D01*
G01D02*
X110320Y507134D01*
G01D02*
G02X113238Y500089I-7044J-7044D01*
G01D02*
Y488596D01*
G01D02*
G02X112577Y486999I-2260J0D01*
G01X102622Y622907D02*
Y516458D01*
G01D02*
G03X105071Y510545I8364J1D01*
G01D02*
X106430Y509186D01*
G01D02*
Y509185D01*
G01D02*
X109401Y506214D01*
G01D02*
G02X111938Y500089I-6125J-6125D01*
G01D02*
Y488597D01*
G01D02*
G02X111657Y487919I-959J0D01*
G01D02*
X111227Y487489D01*
G01D02*
G02X110541Y487205I-686J686D01*
G01D02*
X110532D01*
G01D02*
G03X109735Y486875I0J-1127D01*
G01X99510Y598679D02*
Y516052D01*
G01D02*
G03X102511Y508807I10246J0D01*
G01D02*
X106322Y504996D01*
G01D02*
G02X108538Y499646I-5352J-5351D01*
G01D02*
Y489008D01*
G01D02*
G02X107691Y486962I-2895J0D01*
G01X98210Y598679D02*
Y516051D01*
G01D02*
G03X101591Y507888I11546J1D01*
G01D02*
X105402Y504077D01*
G01D02*
G02X107238Y499645I-4432J-4432D01*
G01D02*
Y489009D01*
G01D02*
G02X106771Y487882I-1594J0D01*
G01X88089Y562998D02*
G02X93534Y549852I-13145J-13145D01*
G01D02*
Y541040D01*
G01D02*
X93990Y540584D01*
G01D02*
Y538984D01*
G01D02*
X93534Y538528D01*
G01D02*
Y536928D01*
G01D02*
X93990Y536472D01*
G01D02*
Y534872D01*
G01D02*
X93534Y534416D01*
G01D02*
Y532816D01*
G01D02*
X93990Y532360D01*
G01D02*
Y530760D01*
G01D02*
X93534Y530304D01*
G01D02*
Y528704D01*
G01D02*
X93990Y528248D01*
G01D02*
Y526648D01*
G01D02*
X93534Y526192D01*
G01D02*
Y523616D01*
G01D02*
X94127Y523024D01*
G01D02*
Y521424D01*
G01D02*
X93534Y520832D01*
G01D02*
Y517036D01*
G01D02*
G03X96768Y509227I11043J-1D01*
G01D02*
X97136Y508860D01*
G01D02*
X102852Y503144D01*
G01D02*
G02X105362Y497084I-6062J-6061D01*
G01D02*
Y489003D01*
G01D02*
G02X104494Y486916I-2938J-2D01*
G01D02*
X104148Y486582D01*
G01X87170Y562078D02*
G02X92234Y549852I-12226J-12226D01*
G01D02*
Y517036D01*
G01D02*
X92235D01*
G01D02*
G03X95849Y508307I12343J-2D01*
G01D02*
X96218Y507939D01*
G01D02*
X101932Y502225D01*
G01D02*
G02X104062Y497083I-5142J-5142D01*
G01D02*
Y489003D01*
G01D02*
G02X103583Y487845I-1637J-1D01*
G01D02*
X102782Y487044D01*
G01D02*
G02X101889Y486674I-893J893D01*
G01D02*
G03X101433Y486485I0J-645D01*
G01X83099Y552826D02*
G02X88441Y539927I-12899J-12898D01*
G01D02*
Y515746D01*
G01D02*
G03X91214Y509051I9468J0D01*
G01D02*
X93709Y506556D01*
G01D02*
Y506555D01*
G01D02*
X97737Y502527D01*
G01D02*
G02X99489Y498297I-4229J-4229D01*
G01D02*
Y487532D01*
G01X82179Y551906D02*
G02X87141Y539927I-11979J-11979D01*
G01D02*
Y515746D01*
G01D02*
G03X90295Y508131I10768J-1D01*
G01D02*
X90294D01*
G01D02*
X96818Y501607D01*
G01D02*
G02X98189Y498297I-3310J-3310D01*
G01D02*
Y488075D01*
G01D02*
G02X97600Y486653I-2011J0D01*
G01D02*
X97185Y486238D01*
G01X79243Y545913D02*
Y534200D01*
G01D02*
X79683Y533760D01*
G01D02*
Y532560D01*
G01D02*
X79243Y532120D01*
G01D02*
Y530920D01*
G01D02*
X79683Y530480D01*
G01D02*
Y529280D01*
G01D02*
X79243Y528840D01*
G01D02*
Y527640D01*
G01D02*
X79683Y527200D01*
G01D02*
Y526000D01*
G01D02*
X79243Y525560D01*
G01D02*
Y524360D01*
G01D02*
X79683Y523920D01*
G01D02*
Y522720D01*
G01D02*
X79243Y522280D01*
G01D02*
Y521080D01*
G01D02*
X79683Y520640D01*
G01D02*
Y519440D01*
G01D02*
X79243Y519000D01*
G01D02*
Y517128D01*
G01D02*
G03X80327Y514513I3699J1D01*
G01D02*
X95182Y499656D01*
G01D02*
Y499596D01*
G01D02*
G02X97377Y493784I-6599J-5813D01*
G01D02*
Y488762D01*
G01D02*
G02X96692Y487108I-2339J0D01*
G01D02*
X95812Y486228D01*
G01D02*
X95750D01*
G01X79407Y513593D02*
X93882Y499117D01*
G01D02*
Y499082D01*
G01D02*
G02X96077Y493783I-5299J-5299D01*
G01D02*
Y488762D01*
G01D02*
G02X95774Y488030I-1035J0D01*
G01D02*
X95160Y487416D01*
G01D02*
G02X94078Y486850I-1444J1444D01*
G01D02*
G03X93514Y486617I-1J-797D01*
G01D02*
X93199Y486301D01*
G01D02*
X93189D01*
G01X116486Y658500D02*
Y608500D01*
G01D02*
X116926Y608060D01*
G01D02*
Y606860D01*
G01D02*
X116486Y606420D01*
G01D02*
Y605220D01*
G01D02*
X116926Y604780D01*
G01D02*
Y603580D01*
G01D02*
X116486Y603140D01*
G01D02*
Y601940D01*
G01D02*
X116926Y601500D01*
G01D02*
Y600300D01*
G01D02*
X116486Y599860D01*
G01D02*
Y598660D01*
G01D02*
X116926Y598220D01*
G01D02*
Y597020D01*
G01D02*
X116486Y596580D01*
G01D02*
Y595380D01*
G01D02*
X116926Y594940D01*
G01D02*
Y593740D01*
G01D02*
X116486Y593300D01*
G01X83531Y645369D02*
X102458Y626442D01*
G01D02*
G02X103922Y622907I-3536J-3535D01*
G01D02*
Y601040D01*
G01D02*
X104362Y600600D01*
G01D02*
Y599400D01*
G01D02*
X103922Y598960D01*
G01D02*
Y597760D01*
G01D02*
X104362Y597320D01*
G01D02*
Y596120D01*
G01D02*
X103922Y595680D01*
G01D02*
Y594480D01*
G01D02*
X104362Y594040D01*
G01D02*
Y592840D01*
G01D02*
X103922Y592400D01*
G01X101538Y625522D02*
G02X102622Y622907I-2615J-2616D01*
G01X78869Y619358D02*
G02X86380Y616247I1J-10621D01*
G01D02*
X96372Y606255D01*
G01D02*
G02X99510Y598679I-7575J-7576D01*
G01X78869Y618058D02*
G02X85460Y615328I0J-9321D01*
G01D02*
X95453Y605335D01*
G01D02*
G02X98210Y598679I-6656J-6656D01*
G01X78292Y578964D02*
Y577131D01*
G01D02*
G03X81357Y569731I10465J0D01*
G01D02*
X88090Y562998D01*
G01D02*
X88089D01*
G01X80437Y568811D02*
X87170Y562078D01*
G01X120618Y700747D02*
G02X122316Y696645I-4103J-4101D01*
G01X119698Y699827D02*
G02X121016Y696645I-3182J-3182D01*
G01X79502Y697860D02*
X80351Y697012D01*
G01D02*
Y696389D01*
G01D02*
X81199Y695541D01*
G01D02*
X81821D01*
G01D02*
X82670Y694692D01*
G01D02*
Y694070D01*
G01D02*
X83088Y693652D01*
G01D02*
G03X83936Y693300I849J849D01*
G01D02*
X96761D01*
G01D02*
G02X99449Y692188I1J-3802D01*
G01D02*
X114788Y676849D01*
G01D02*
G02X116486Y672747I-4103J-4101D01*
G01D02*
Y670420D01*
G01D02*
X116926Y669980D01*
G01D02*
Y668780D01*
G01D02*
X116486Y668340D01*
G01D02*
Y667140D01*
G01D02*
X116926Y666700D01*
G01D02*
Y665500D01*
G01D02*
X116486Y665060D01*
G01D02*
Y663860D01*
G01D02*
X116926Y663420D01*
G01D02*
Y662220D01*
G01D02*
X116486Y661780D01*
G01D02*
Y660580D01*
G01D02*
X116926Y660140D01*
G01D02*
Y658940D01*
G01D02*
X116486Y658500D01*
G01X82168Y692732D02*
G03X83936Y692000I1768J1769D01*
G01D02*
X96761D01*
G01D02*
G02X98529Y691268I0J-2501D01*
G01D02*
X113868Y675929D01*
G01D02*
G02X115186Y672747I-3182J-3182D01*
G01X84637Y686722D02*
G03X86899Y685784I2263J2262D01*
G01D02*
X92853D01*
G01D02*
G02X96955Y684086I1J-5801D01*
G01D02*
X110459Y670582D01*
G01D02*
G02X112157Y666480I-4103J-4101D01*
G01X83717Y685802D02*
G03X86898Y684484I3182J3182D01*
G01D02*
X92853D01*
G01D02*
G02X96035Y683166I0J-4500D01*
G01D02*
X109539Y669662D01*
G01D02*
G02X110857Y666480I-3182J-3182D01*
G01X78892Y650630D02*
Y650008D01*
G01D02*
X79741Y649159D01*
G01D02*
X80363D01*
G01D02*
X81211Y648311D01*
G01D02*
Y647689D01*
G01D02*
X82060Y646840D01*
G01D02*
X82682D01*
G01D02*
X83531Y645992D01*
G01D02*
Y645369D01*
G01X188495Y777414D02*
X142288Y731207D01*
G01D02*
G03X141350Y728945I2262J-2263D01*
G01X187575Y778334D02*
X141368Y732127D01*
G01D02*
G03X140050Y728945I3182J-3182D01*
G01X185054Y782249D02*
X136916Y734111D01*
G01D02*
G03X135598Y730929I3182J-3182D01*
G01X184134Y783169D02*
X135996Y735031D01*
G01D02*
G03X134298Y730929I4103J-4101D01*
G01X179234Y784880D02*
X143224Y748870D01*
G01D02*
Y748250D01*
G01D02*
X142375Y747401D01*
G01D02*
X141753D01*
G01D02*
X140905Y746553D01*
G01D02*
Y745930D01*
G01D02*
X140056Y745082D01*
G01D02*
X139434D01*
G01D02*
X138585Y744233D01*
G01D02*
Y743611D01*
G01D02*
X137737Y742763D01*
G01D02*
X137115D01*
G01D02*
X136266Y741914D01*
G01D02*
Y741292D01*
G01D02*
X135418Y740443D01*
G01D02*
X134795D01*
G01D02*
X133947Y739595D01*
G01D02*
Y738973D01*
G01D02*
X133098Y738124D01*
G01D02*
X132476D01*
G01D02*
X131862Y737510D01*
G01D02*
G03X130544Y734328I3182J-3182D01*
G01X178314Y785800D02*
X130944Y738430D01*
G01D02*
X130942D01*
G01D02*
G03X129244Y734328I4103J-4101D01*
G01X126783Y801701D02*
Y751600D01*
G01D02*
X127223Y751160D01*
G01D02*
Y749960D01*
G01D02*
X126783Y749520D01*
G01D02*
Y748320D01*
G01D02*
X127223Y747880D01*
G01D02*
Y746680D01*
G01D02*
X126783Y746240D01*
G01D02*
Y745040D01*
G01D02*
X127223Y744600D01*
G01D02*
Y743400D01*
G01D02*
X126783Y742960D01*
G01D02*
Y741760D01*
G01D02*
X127223Y741320D01*
G01D02*
Y740120D01*
G01D02*
X126783Y739680D01*
G01D02*
Y738480D01*
G01D02*
X127223Y738040D01*
G01D02*
Y736840D01*
G01D02*
X126783Y736400D01*
G01X82332Y736629D02*
G02X86434Y734931I1J-5801D01*
G01D02*
X120618Y700747D01*
G01X82332Y735329D02*
G02X85514Y734011I0J-4500D01*
G01D02*
X119698Y699827D01*
G01X78880Y697860D02*
X79502D01*
G01X150690Y837095D02*
X146881D01*
G01D02*
G02Y845299I0J4102D01*
G01X148722Y830793D02*
G03X148034Y831481I-688J0D01*
G01D02*
X147311D01*
G01D02*
G03X146082Y830972I0J-1738D01*
G01D02*
X144185Y829075D01*
G01D02*
G03X143306Y826953I2122J-2122D01*
G01D02*
Y826852D01*
G01D02*
G03X144114Y824902I2757J0D01*
G01D02*
G03X146062Y824095I1948J1948D01*
G01D02*
X161964D01*
G01X150801Y832781D02*
X147311D01*
G01D02*
G03X145162Y831892I-1J-3039D01*
G01D02*
X143265Y829995D01*
G01D02*
G03X142006Y826953I3042J-3041D01*
G01D02*
Y826852D01*
G01D02*
G03X143194Y823982I4058J-1D01*
G01D02*
G03X146062Y822795I2867J2868D01*
G01D02*
X161965D01*
G01X148762Y817900D02*
X142982D01*
G01D02*
G03X139800Y816582I0J-4500D01*
G01D02*
Y815960D01*
G01D02*
X138951Y815111D01*
G01D02*
X138329D01*
G01D02*
X137481Y814263D01*
G01D02*
Y813640D01*
G01D02*
X136632Y812792D01*
G01D02*
X136010D01*
G01D02*
X135161Y811943D01*
G01D02*
Y811321D01*
G01D02*
X134313Y810473D01*
G01D02*
X133691D01*
G01D02*
X132842Y809624D01*
G01D02*
Y809002D01*
G01D02*
X131994Y808153D01*
G01D02*
X131371D01*
G01D02*
X130523Y807305D01*
G01D02*
Y806683D01*
G01D02*
X129674Y805834D01*
G01D02*
X129052D01*
G01D02*
X128101Y804883D01*
G01D02*
G03X126783Y801701I3182J-3182D01*
G01X148761Y819200D02*
X142982D01*
G01D02*
G03X138880Y817502I-1J-5801D01*
G01D02*
X127181Y805803D01*
G01D02*
G03X125483Y801701I4103J-4101D01*
G01X151611Y850210D02*
X145430D01*
G01D02*
G02X141328Y851908I-1J5801D01*
G01D02*
X140154Y853082D01*
G01D02*
G02X138456Y857184I4103J4101D01*
G01D02*
Y862519D01*
G01D02*
G02X138707Y863697I2886J1D01*
G01D02*
X138922Y864215D01*
G01D02*
G02X140458Y865752I2626J-1088D01*
G01D02*
X141047Y865996D01*
G01D02*
G02X142146Y866215I1100J-2655D01*
G01D02*
X173686D01*
G01X148881Y851510D02*
X145430D01*
G01D02*
G02X142248Y852828I0J4500D01*
G01D02*
X141074Y854002D01*
G01D02*
G02X139757Y857184I3183J3181D01*
G01D02*
X139756Y857183D01*
G01D02*
Y862519D01*
G01D02*
G02X139878Y863129I1586J0D01*
G01D02*
X139880Y863131D01*
G01D02*
X140123Y863717D01*
G01D02*
G02X140956Y864551I1425J-590D01*
G01D02*
X141545Y864795D01*
G01D02*
G02X142147Y864915I603J-1454D01*
G01D02*
X173687D01*
G01X146881Y845299D02*
X156995D01*
G01X149343Y840895D02*
G03X148333Y839885I0J-1010D01*
G01D02*
Y839063D01*
G01D02*
G02X147665Y838395I-668J0D01*
G01D02*
X146881D01*
G01D02*
G02Y843999I0J2802D01*
G01D02*
X156993D01*
G01X221195Y317105D02*
X171195D01*
G01D02*
X170755Y317545D01*
G01D02*
X169555D01*
G01D02*
X169115Y317105D01*
G01D02*
X167915D01*
G01D02*
X167475Y317545D01*
G01D02*
X166275D01*
G01D02*
X165835Y317105D01*
G01D02*
X164635D01*
G01D02*
X164195Y317545D01*
G01D02*
X162995D01*
G01D02*
X162555Y317105D01*
G01D02*
X161355D01*
G01D02*
X160915Y317545D01*
G01D02*
X159715D01*
G01D02*
X159275Y317105D01*
G01D02*
X158075D01*
G01D02*
X157635Y317545D01*
G01D02*
X156435D01*
G01D02*
X155995Y317105D01*
G01D02*
X149443D01*
G01X738903Y315805D02*
X149442D01*
G01X151508Y325091D02*
G03X154690Y323773I3182J3182D01*
G01D02*
X158100D01*
G01D02*
X158540Y324213D01*
G01D02*
X159740D01*
G01D02*
X160180Y323773D01*
G01D02*
X161380D01*
G01D02*
X161820Y324213D01*
G01D02*
X163020D01*
G01D02*
X163460Y323773D01*
G01D02*
X164660D01*
G01D02*
X165100Y324213D01*
G01D02*
X166300D01*
G01D02*
X166740Y323773D01*
G01D02*
X167940D01*
G01D02*
X168380Y324213D01*
G01D02*
X169580D01*
G01D02*
X170020Y323773D01*
G01D02*
X171220D01*
G01D02*
X171660Y324213D01*
G01D02*
X172860D01*
G01D02*
X173300Y323773D01*
G01D02*
X223300D01*
G01X150588Y324171D02*
G03X154690Y322473I4101J4103D01*
G01D02*
X730652D01*
G01X159701Y329773D02*
X165400D01*
G01D02*
X165840Y330213D01*
G01D02*
X167040D01*
G01D02*
X167480Y329773D01*
G01D02*
X168680D01*
G01D02*
X169120Y330213D01*
G01D02*
X170320D01*
G01D02*
X170760Y329773D01*
G01D02*
X171960D01*
G01D02*
X172400Y330213D01*
G01D02*
X173600D01*
G01D02*
X174040Y329773D01*
G01D02*
X175240D01*
G01D02*
X175680Y330213D01*
G01D02*
X176880D01*
G01D02*
X177320Y329773D01*
G01D02*
X178520D01*
G01D02*
X178960Y330213D01*
G01D02*
X180160D01*
G01D02*
X180600Y329773D01*
G01D02*
X230600D01*
G01X159701Y328473D02*
X719456D01*
G01X162691Y338173D02*
X165900D01*
G01D02*
X166340Y338613D01*
G01D02*
X167540D01*
G01D02*
X167980Y338173D01*
G01D02*
X169180D01*
G01D02*
X169620Y338613D01*
G01D02*
X170820D01*
G01D02*
X171260Y338173D01*
G01D02*
X172460D01*
G01D02*
X172900Y338613D01*
G01D02*
X174100D01*
G01D02*
X174540Y338173D01*
G01D02*
X175740D01*
G01D02*
X176180Y338613D01*
G01D02*
X177380D01*
G01D02*
X177820Y338173D01*
G01D02*
X179020D01*
G01D02*
X179460Y338613D01*
G01D02*
X180660D01*
G01D02*
X181100Y338173D01*
G01D02*
X231100D01*
G01X162692Y336873D02*
X705136D01*
G01X162853Y344573D02*
X168200D01*
G01D02*
X168640Y345013D01*
G01D02*
X169840D01*
G01D02*
X170280Y344573D01*
G01D02*
X171480D01*
G01D02*
X171920Y345013D01*
G01D02*
X173120D01*
G01D02*
X173560Y344573D01*
G01D02*
X174760D01*
G01D02*
X175200Y345013D01*
G01D02*
X176400D01*
G01D02*
X176840Y344573D01*
G01D02*
X178040D01*
G01D02*
X178480Y345013D01*
G01D02*
X179680D01*
G01D02*
X180120Y344573D01*
G01D02*
X181320D01*
G01D02*
X181760Y345013D01*
G01D02*
X182960D01*
G01D02*
X183400Y344573D01*
G01D02*
X233400D01*
G01X162854Y343273D02*
X692770D01*
G01X150317Y366587D02*
G03X152579Y365649I2263J2262D01*
G01D02*
X433585D01*
G01X149397Y365667D02*
G03X152579Y364349I3182J3182D01*
G01D02*
X433585D01*
G01X148719Y374485D02*
X148721D01*
G01X150940Y372266D02*
G03X154122Y370948I3182J3182D01*
G01D02*
X431384D01*
G01X150020Y371346D02*
G03X154122Y369648I4101J4103D01*
G01D02*
X431384D01*
G01X426294Y378457D02*
X155500D01*
G01D02*
G02X154365Y378927I0J1605D01*
G01D02*
X152881Y380412D01*
G01X426293Y377157D02*
X155500D01*
G01D02*
G02X153444Y378008I-1J2907D01*
G01D02*
X152926Y378527D01*
G01X149583Y398383D02*
G02X149014Y397009I-1943J0D01*
G01X152791Y384731D02*
G03X155053Y383793I2263J2262D01*
G01D02*
X421015D01*
G01X149488Y402114D02*
X148831Y401458D01*
G01X151871Y383811D02*
G03X155053Y382493I3182J3182D01*
G01D02*
X421015D01*
G01X160628Y352200D02*
X170380D01*
G01D02*
X170820Y352640D01*
G01D02*
X172020D01*
G01D02*
X172460Y352200D01*
G01D02*
X173660D01*
G01D02*
X174100Y352640D01*
G01D02*
X175300D01*
G01D02*
X175740Y352200D01*
G01D02*
X176940D01*
G01D02*
X177380Y352640D01*
G01D02*
X178580D01*
G01D02*
X179020Y352200D01*
G01D02*
X180220D01*
G01D02*
X180660Y352640D01*
G01D02*
X181860D01*
G01D02*
X182300Y352200D01*
G01D02*
X232300D01*
G01X160628Y350900D02*
X681499D01*
G01X150356Y361065D02*
G03X153538Y359747I3182J3182D01*
G01D02*
X156500D01*
G01D02*
X156940Y360187D01*
G01D02*
X158140D01*
G01D02*
X158580Y359747D01*
G01D02*
X159780D01*
G01D02*
X160220Y360187D01*
G01D02*
X161420D01*
G01D02*
X161860Y359747D01*
G01D02*
X163060D01*
G01D02*
X163500Y360187D01*
G01D02*
X164700D01*
G01D02*
X165140Y359747D01*
G01D02*
X166340D01*
G01D02*
X166780Y360187D01*
G01D02*
X167980D01*
G01D02*
X168420Y359747D01*
G01D02*
X169620D01*
G01D02*
X170060Y360187D01*
G01D02*
X171260D01*
G01D02*
X171700Y359747D01*
G01D02*
X221700D01*
G01X149436Y360145D02*
G03X153538Y358447I4101J4103D01*
G01D02*
X671650D01*
G01X152662Y376038D02*
G03X155844Y374720I3182J3182D01*
G01D02*
X429157D01*
G01X151742Y375118D02*
G03X155844Y373420I4101J4103D01*
G01D02*
X429156D01*
G01X157486Y484968D02*
Y485372D01*
G01D02*
G02X158045Y486722I1909J0D01*
G01X157508Y480990D02*
X157635Y481116D01*
G01D02*
G03X159425Y485439I-4323J4322D01*
G01D02*
G02X160060Y486972I2168J0D01*
G01X153586Y485118D02*
G03X153853Y485464I-1212J1212D01*
G01D02*
G03X154088Y486330I-1479J866D01*
G01X153601Y480894D02*
X154054Y481346D01*
G01D02*
G03X155388Y484568I-3222J3221D01*
G01D02*
Y493829D01*
G01X149620Y485149D02*
Y485796D01*
G01D02*
G02X150041Y486812I1437J0D01*
G01X149594Y480923D02*
G03X151320Y485090I-4167J4167D01*
G01D02*
Y485641D01*
G01D02*
G02X151751Y486682I1472J0D01*
G01X158045Y486722D02*
X158815Y487493D01*
G01D02*
G03X159186Y488387I-894J895D01*
G01D02*
Y489772D01*
G01D02*
G03X158761Y490798I-1451J0D01*
G01D02*
G02X158500Y491113I1544J1545D01*
G01D02*
G02X158119Y492351I1814J1236D01*
G01D02*
Y492709D01*
G01D02*
G02X159260Y495465I3899J0D01*
G01D02*
X252414Y588619D01*
G01X160060Y486972D02*
G03X160486Y488387I-2140J1416D01*
G01D02*
Y489773D01*
G01D02*
G03X159681Y491718I-2752J0D01*
G01D02*
G02X159419Y492351I633J633D01*
G01D02*
Y492708D01*
G01D02*
G02X160180Y494545I2598J0D01*
G01D02*
X160644Y495009D01*
G01D02*
X160645D01*
G01D02*
X252582Y586947D01*
G01X154088Y486330D02*
Y493830D01*
G01D02*
G02X158080Y503468I13632J-1D01*
G01D02*
Y503469D01*
G01D02*
X251972Y597361D01*
G01X155388Y493829D02*
G02X159000Y502549I12332J0D01*
G01D02*
X252892Y596441D01*
G01X150041Y486812D02*
X150878Y487649D01*
G01D02*
G03X151312Y488697I-1048J1048D01*
G01D02*
Y499821D01*
G01D02*
X151313D01*
G01D02*
G02X156886Y513278I19028J2D01*
G01D02*
X157024Y513415D01*
G01D02*
X246800Y603191D01*
G01X151751Y486682D02*
X151798Y486729D01*
G01D02*
G03X152612Y488697I-1969J1967D01*
G01D02*
Y499821D01*
G01D02*
G02X157804Y512357I17728J1D01*
G01D02*
X157940Y512492D01*
G01D02*
X247720Y602272D01*
G01X253997Y621147D02*
X151215Y518365D01*
G01X254916Y620226D02*
X152135Y517445D01*
G01X154190Y837095D02*
G02X158726Y838974I4536J-4536D01*
G01X154301Y828981D02*
X155510Y830190D01*
G01D02*
G02X156500Y830600I990J-990D01*
G01D02*
X157913D01*
G01D02*
G02X158611Y830311I0J-987D01*
G01D02*
X159688Y829234D01*
G01X154301Y832781D02*
X154815Y832266D01*
G01D02*
G03X155700Y831900I884J885D01*
G01D02*
X158278D01*
G01D02*
G03X159688Y832484I0J1994D01*
G01X155786Y814140D02*
G03X156469Y814423I0J966D01*
G01D02*
X159589Y817543D01*
G01X155786Y817740D02*
X156497D01*
G01D02*
G03X157851Y818301I0J1915D01*
G01D02*
X158844Y819294D01*
G01D02*
G03X159137Y820001I-706J707D01*
G01D02*
Y820712D01*
G01X190193Y849708D02*
Y781516D01*
G01D02*
G02X188495Y777414I-5801J-1D01*
G01X188893Y849708D02*
Y781516D01*
G01D02*
G02X187575Y778334I-4500J0D01*
G01X184674Y839360D02*
G02X186372Y835258I-4103J-4101D01*
G01D02*
Y785430D01*
G01D02*
G02X185054Y782249I-4500J1D01*
G01X183754Y838440D02*
G02X185072Y835258I-3182J-3182D01*
G01D02*
Y785431D01*
G01D02*
G02X184134Y783169I-3200J1D01*
G01X150801Y828981D02*
X149383D01*
G01D02*
G02X148722Y829642I0J661D01*
G01D02*
Y830793D01*
G01X161964Y824095D02*
G02X166066Y822397I1J-5801D01*
G01D02*
X178854Y809609D01*
G01D02*
G02X180552Y805507I-4103J-4101D01*
G01D02*
Y803262D01*
G01D02*
X180992Y802822D01*
G01D02*
Y801622D01*
G01D02*
X180552Y801182D01*
G01D02*
Y799982D01*
G01D02*
X180992Y799542D01*
G01D02*
Y798342D01*
G01D02*
X180552Y797902D01*
G01D02*
Y796702D01*
G01D02*
X180992Y796262D01*
G01D02*
Y795062D01*
G01D02*
X180552Y794622D01*
G01D02*
Y793422D01*
G01D02*
X180992Y792982D01*
G01D02*
Y791782D01*
G01D02*
X180552Y791342D01*
G01D02*
Y790142D01*
G01D02*
X180992Y789702D01*
G01D02*
Y788502D01*
G01D02*
X180552Y788062D01*
G01D02*
G02X179234Y784880I-4500J0D01*
G01X161965Y822795D02*
G02X165146Y821477I-1J-4500D01*
G01D02*
X177934Y808689D01*
G01D02*
G02X179251Y805507I-3183J-3181D01*
G01D02*
X179252Y805508D01*
G01D02*
Y788062D01*
G01D02*
G02X178314Y785800I-3200J1D01*
G01X152286Y814140D02*
X151242D01*
G01D02*
G02X150089Y815293I0J1153D01*
G01D02*
Y817019D01*
G01D02*
G03X149239Y817869I-850J0D01*
G01D02*
X149237D01*
G01D02*
G03X148762Y817900I-477J-3654D01*
G01X152286Y817740D02*
G03X148761Y819200I-3525J-3525D01*
G01X155111Y850210D02*
X156949D01*
G01D02*
G02X158014Y849769I0J-1506D01*
G01D02*
X159426Y848357D01*
G01X155038Y853750D02*
G02X156275Y853237I-1J-1750D01*
G01D02*
X157280Y852233D01*
G01D02*
G03X159060Y851564I1779J2032D01*
G01D02*
X159688D01*
G01X158726Y838974D02*
X159431D01*
G01X153990Y840895D02*
X157216D01*
G01D02*
G03X159038Y841649I1J2576D01*
G01D02*
X159560Y842172D01*
G01X173686Y866215D02*
G02X177788Y864517I1J-5801D01*
G01D02*
X188495Y853810D01*
G01D02*
G02X190193Y849708I-4103J-4101D01*
G01X151538Y853750D02*
X150262D01*
G01D02*
G03X149696Y853184I0J-566D01*
G01D02*
Y852325D01*
G01D02*
G02X148881Y851510I-815J0D01*
G01X173687Y864915D02*
G02X176868Y863597I-1J-4500D01*
G01D02*
X187575Y852890D01*
G01D02*
G02X188893Y849708I-3182J-3182D01*
G01X156995Y845299D02*
G03X157751Y845441I0J2082D01*
G01D02*
X158428Y845705D01*
G01D02*
G02X159599Y845926I1172J-2998D01*
G01D02*
X175707D01*
G01D02*
G02X179808Y844227I-1J-5801D01*
G01D02*
X184674Y839360D01*
G01X150490Y840895D02*
X149343D01*
G01X156993Y843999D02*
G03X158223Y844229I4J3382D01*
G01D02*
X158901Y844494D01*
G01D02*
G02X159600Y844626I699J-1787D01*
G01D02*
X175706D01*
G01D02*
G02X178888Y843307I-1J-4500D01*
G01D02*
X183754Y838440D01*
G01X289675Y317105D02*
X288475D01*
G01D02*
X288035Y317545D01*
G01D02*
X286835D01*
G01D02*
X286395Y317105D01*
G01D02*
X236395D01*
G01D02*
X235955Y317545D01*
G01D02*
X234755D01*
G01D02*
X234315Y317105D01*
G01D02*
X233115D01*
G01D02*
X232675Y317545D01*
G01D02*
X231475D01*
G01D02*
X231035Y317105D01*
G01D02*
X229835D01*
G01D02*
X229395Y317545D01*
G01D02*
X228195D01*
G01D02*
X227755Y317105D01*
G01D02*
X226555D01*
G01D02*
X226115Y317545D01*
G01D02*
X224915D01*
G01D02*
X224475Y317105D01*
G01D02*
X223275D01*
G01D02*
X222835Y317545D01*
G01D02*
X221635D01*
G01D02*
X221195Y317105D01*
G01X223300Y323773D02*
X223740Y324213D01*
G01D02*
X224940D01*
G01D02*
X225380Y323773D01*
G01D02*
X226580D01*
G01D02*
X227020Y324213D01*
G01D02*
X228220D01*
G01D02*
X228660Y323773D01*
G01D02*
X229860D01*
G01D02*
X230300Y324213D01*
G01D02*
X231500D01*
G01D02*
X231940Y323773D01*
G01D02*
X233140D01*
G01D02*
X233580Y324213D01*
G01D02*
X234780D01*
G01D02*
X235220Y323773D01*
G01D02*
X236420D01*
G01D02*
X236860Y324213D01*
G01D02*
X238060D01*
G01D02*
X238500Y323773D01*
G01D02*
X288500D01*
G01D02*
X288940Y324213D01*
G01D02*
X290140D01*
G01X230600Y329773D02*
X231040Y330213D01*
G01D02*
X232240D01*
G01D02*
X232680Y329773D01*
G01D02*
X233880D01*
G01D02*
X234320Y330213D01*
G01D02*
X235520D01*
G01D02*
X235960Y329773D01*
G01D02*
X237160D01*
G01D02*
X237600Y330213D01*
G01D02*
X238800D01*
G01D02*
X239240Y329773D01*
G01D02*
X240440D01*
G01D02*
X240880Y330213D01*
G01D02*
X242080D01*
G01D02*
X242520Y329773D01*
G01D02*
X243720D01*
G01D02*
X244160Y330213D01*
G01D02*
X245360D01*
G01D02*
X245800Y329773D01*
G01D02*
X295800D01*
G01X231100Y338173D02*
X231540Y338613D01*
G01D02*
X232740D01*
G01D02*
X233180Y338173D01*
G01D02*
X234380D01*
G01D02*
X234820Y338613D01*
G01D02*
X236020D01*
G01D02*
X236460Y338173D01*
G01D02*
X237660D01*
G01D02*
X238100Y338613D01*
G01D02*
X239300D01*
G01D02*
X239740Y338173D01*
G01D02*
X240940D01*
G01D02*
X241380Y338613D01*
G01D02*
X242580D01*
G01D02*
X243020Y338173D01*
G01D02*
X296300D01*
G01X233400Y344573D02*
X233840Y345013D01*
G01D02*
X235040D01*
G01D02*
X235480Y344573D01*
G01D02*
X236680D01*
G01D02*
X237120Y345013D01*
G01D02*
X238320D01*
G01D02*
X238760Y344573D01*
G01D02*
X239960D01*
G01D02*
X240400Y345013D01*
G01D02*
X241600D01*
G01D02*
X242040Y344573D01*
G01D02*
X243240D01*
G01D02*
X243680Y345013D01*
G01D02*
X244880D01*
G01D02*
X245320Y344573D01*
G01D02*
X298600D01*
G01X232300Y352200D02*
X232740Y352640D01*
G01D02*
X233940D01*
G01D02*
X234380Y352200D01*
G01D02*
X235580D01*
G01D02*
X236020Y352640D01*
G01D02*
X237220D01*
G01D02*
X237660Y352200D01*
G01D02*
X238860D01*
G01D02*
X239300Y352640D01*
G01D02*
X240500D01*
G01D02*
X240940Y352200D01*
G01D02*
X242140D01*
G01D02*
X242580Y352640D01*
G01D02*
X243780D01*
G01D02*
X244220Y352200D01*
G01D02*
X245420D01*
G01D02*
X245860Y352640D01*
G01D02*
X247060D01*
G01D02*
X247500Y352200D01*
G01D02*
X297500D01*
G01X221700Y359747D02*
X222140Y360187D01*
G01D02*
X223340D01*
G01D02*
X223780Y359747D01*
G01D02*
X224980D01*
G01D02*
X225420Y360187D01*
G01D02*
X226620D01*
G01D02*
X227060Y359747D01*
G01D02*
X228260D01*
G01D02*
X228700Y360187D01*
G01D02*
X229900D01*
G01D02*
X230340Y359747D01*
G01D02*
X231540D01*
G01D02*
X231980Y360187D01*
G01D02*
X233180D01*
G01D02*
X233620Y359747D01*
G01D02*
X286900D01*
G01D02*
X287340Y360187D01*
G01D02*
X288540D01*
G01D02*
X288980Y359747D01*
G01D02*
X290180D01*
G01X252414Y588619D02*
G02X273403Y597313I20989J-20989D01*
G01D02*
X280480D01*
G01D02*
X280920Y597753D01*
G01D02*
X282120D01*
G01D02*
X282560Y597313D01*
G01D02*
X283760D01*
G01D02*
X284200Y597753D01*
G01D02*
X285400D01*
G01D02*
X285840Y597313D01*
G01D02*
X287040D01*
G01D02*
X287480Y597753D01*
G01D02*
X288680D01*
G01D02*
X289120Y597313D01*
G01D02*
X290320D01*
G01X252582Y586947D02*
X253336Y587700D01*
G01D02*
G02X273404Y596013I20069J-20068D01*
G01D02*
X747523D01*
G01X251972Y597361D02*
G02X267241Y603685I15269J-15271D01*
G01D02*
X271041D01*
G01D02*
X271441Y604085D01*
G01D02*
X272441D01*
G01D02*
X272841Y603685D01*
G01D02*
X273841D01*
G01D02*
X274241Y604085D01*
G01D02*
X275241D01*
G01D02*
X275641Y603685D01*
G01D02*
X276641D01*
G01D02*
X277041Y604085D01*
G01D02*
X278041D01*
G01D02*
X278441Y603685D01*
G01D02*
X279441D01*
G01D02*
X279841Y604085D01*
G01D02*
X280841D01*
G01D02*
X281241Y603685D01*
G01D02*
X282241D01*
G01D02*
X282641Y604085D01*
G01D02*
X283641D01*
G01D02*
X284041Y603685D01*
G01D02*
X768722D01*
G01X252892Y596441D02*
G02X267242Y602385I14350J-14350D01*
G01D02*
X781514D01*
G01X246800Y603191D02*
G02X288226Y620350I41425J-41425D01*
G01D02*
X289226D01*
G01D02*
X289626Y620750D01*
G01X247720Y602272D02*
G02X288226Y619050I40506J-40506D01*
G01D02*
X770099D01*
G01X291058Y636497D02*
G03X253997Y621146I1J-52414D01*
G01D02*
Y621147D01*
G01X291059Y635197D02*
G03X254916Y620226I0J-51114D01*
G01X360200Y317105D02*
X359705Y317600D01*
G01D02*
X358600D01*
G01D02*
X358105Y317105D01*
G01D02*
X356955D01*
G01D02*
X356515Y317545D01*
G01D02*
X355315D01*
G01D02*
X354875Y317105D01*
G01D02*
X353675D01*
G01D02*
X353235Y317545D01*
G01D02*
X352035D01*
G01D02*
X351595Y317105D01*
G01D02*
X301595D01*
G01D02*
X301155Y317545D01*
G01D02*
X299955D01*
G01D02*
X299515Y317105D01*
G01D02*
X298315D01*
G01D02*
X297875Y317545D01*
G01D02*
X296675D01*
G01D02*
X296235Y317105D01*
G01D02*
X295035D01*
G01D02*
X294595Y317545D01*
G01D02*
X293395D01*
G01D02*
X292955Y317105D01*
G01D02*
X291755D01*
G01D02*
X291315Y317545D01*
G01D02*
X290115D01*
G01D02*
X289675Y317105D01*
G01X290140Y324213D02*
X290580Y323773D01*
G01D02*
X291780D01*
G01D02*
X292220Y324213D01*
G01D02*
X293420D01*
G01D02*
X293860Y323773D01*
G01D02*
X295060D01*
G01D02*
X295500Y324213D01*
G01D02*
X296700D01*
G01D02*
X297140Y323773D01*
G01D02*
X298340D01*
G01D02*
X298780Y324213D01*
G01D02*
X299980D01*
G01D02*
X300420Y323773D01*
G01D02*
X301620D01*
G01D02*
X302060Y324213D01*
G01D02*
X303260D01*
G01D02*
X303700Y323773D01*
G01D02*
X353700D01*
G01D02*
X354140Y324213D01*
G01D02*
X355340D01*
G01D02*
X355780Y323773D01*
G01D02*
X356980D01*
G01D02*
X357420Y324213D01*
G01D02*
X358620D01*
G01D02*
X359060Y323773D01*
G01D02*
X360260D01*
G01X295800Y329773D02*
X296240Y330213D01*
G01D02*
X297440D01*
G01D02*
X297880Y329773D01*
G01D02*
X299080D01*
G01D02*
X299520Y330213D01*
G01D02*
X300720D01*
G01D02*
X301160Y329773D01*
G01D02*
X302360D01*
G01D02*
X302800Y330213D01*
G01D02*
X304000D01*
G01D02*
X304440Y329773D01*
G01D02*
X305640D01*
G01D02*
X306080Y330213D01*
G01D02*
X307280D01*
G01D02*
X307720Y329773D01*
G01D02*
X308920D01*
G01D02*
X309360Y330213D01*
G01D02*
X310560D01*
G01D02*
X311000Y329773D01*
G01D02*
X361000D01*
G01X296300Y338173D02*
X296740Y338613D01*
G01D02*
X297940D01*
G01D02*
X298380Y338173D01*
G01D02*
X299580D01*
G01D02*
X300020Y338613D01*
G01D02*
X301220D01*
G01D02*
X301660Y338173D01*
G01D02*
X302860D01*
G01D02*
X303300Y338613D01*
G01D02*
X304500D01*
G01D02*
X304940Y338173D01*
G01D02*
X306140D01*
G01D02*
X306580Y338613D01*
G01D02*
X307780D01*
G01D02*
X308220Y338173D01*
G01D02*
X361500D01*
G01X298600Y344573D02*
X299040Y345013D01*
G01D02*
X300240D01*
G01D02*
X300680Y344573D01*
G01D02*
X301880D01*
G01D02*
X302320Y345013D01*
G01D02*
X303520D01*
G01D02*
X303960Y344573D01*
G01D02*
X305160D01*
G01D02*
X305600Y345013D01*
G01D02*
X306800D01*
G01D02*
X307240Y344573D01*
G01D02*
X308440D01*
G01D02*
X308880Y345013D01*
G01D02*
X310080D01*
G01D02*
X310520Y344573D01*
G01D02*
X363800D01*
G01X297500Y352200D02*
X297940Y352640D01*
G01D02*
X299140D01*
G01D02*
X299580Y352200D01*
G01D02*
X300780D01*
G01D02*
X301220Y352640D01*
G01D02*
X302420D01*
G01D02*
X302860Y352200D01*
G01D02*
X304060D01*
G01D02*
X304500Y352640D01*
G01D02*
X305700D01*
G01D02*
X306140Y352200D01*
G01D02*
X307340D01*
G01D02*
X307780Y352640D01*
G01D02*
X308980D01*
G01D02*
X309420Y352200D01*
G01D02*
X362700D01*
G01X290180Y359747D02*
X290620Y360187D01*
G01D02*
X291820D01*
G01D02*
X292260Y359747D01*
G01D02*
X293460D01*
G01D02*
X293900Y360187D01*
G01D02*
X295100D01*
G01D02*
X295540Y359747D01*
G01D02*
X296740D01*
G01D02*
X297180Y360187D01*
G01D02*
X298380D01*
G01D02*
X298820Y359747D01*
G01D02*
X352100D01*
G01D02*
X352540Y360187D01*
G01D02*
X353740D01*
G01D02*
X354180Y359747D01*
G01D02*
X355380D01*
G01D02*
X355820Y360187D01*
G01D02*
X357020D01*
G01D02*
X357460Y359747D01*
G01D02*
X358660D01*
G01D02*
X359100Y360187D01*
G01D02*
X360300D01*
G01X290320Y597313D02*
X290760Y597753D01*
G01D02*
X291960D01*
G01D02*
X292400Y597313D01*
G01D02*
X342400D01*
G01D02*
X342840Y597753D01*
G01D02*
X344040D01*
G01D02*
X344480Y597313D01*
G01D02*
X345680D01*
G01D02*
X346120Y597753D01*
G01D02*
X347320D01*
G01D02*
X347760Y597313D01*
G01D02*
X747523D01*
G01X289626Y620750D02*
X290626D01*
G01D02*
X291026Y620350D01*
G01D02*
X292026D01*
G01D02*
X292426Y620750D01*
G01D02*
X293426D01*
G01D02*
X293826Y620350D01*
G01D02*
X294826D01*
G01D02*
X295226Y620750D01*
G01D02*
X296226D01*
G01D02*
X296626Y620350D01*
G01D02*
X297626D01*
G01D02*
X298026Y620750D01*
G01D02*
X299026D01*
G01D02*
X299426Y620350D01*
G01D02*
X300426D01*
G01D02*
X300826Y620750D01*
G01D02*
X301826D01*
G01D02*
X302226Y620350D01*
G01D02*
X303226D01*
G01D02*
X303626Y620750D01*
G01D02*
X304626D01*
G01D02*
X305026Y620350D01*
G01D02*
X769634D01*
G01X360297Y636900D02*
X359250D01*
G01D02*
X358847Y636497D01*
G01D02*
X357618D01*
G01D02*
X357178Y636937D01*
G01D02*
X355978D01*
G01D02*
X355538Y636497D01*
G01D02*
X354338D01*
G01D02*
X353898Y636937D01*
G01D02*
X352698D01*
G01D02*
X352258Y636497D01*
G01D02*
X302258D01*
G01D02*
X301858Y636897D01*
G01D02*
X300858D01*
G01D02*
X300458Y636497D01*
G01D02*
X299458D01*
G01D02*
X299058Y636897D01*
G01D02*
X298058D01*
G01D02*
X297658Y636497D01*
G01D02*
X296658D01*
G01D02*
X296258Y636897D01*
G01D02*
X295258D01*
G01D02*
X294858Y636497D01*
G01D02*
X293858D01*
G01D02*
X293458Y636897D01*
G01D02*
X292458D01*
G01D02*
X292058Y636497D01*
G01D02*
X291058D01*
G01X769572Y635197D02*
X291059D01*
G01X738903Y317105D02*
X360200D01*
G01X360260Y323773D02*
X360700Y324213D01*
G01D02*
X361900D01*
G01D02*
X362340Y323773D01*
G01D02*
X730651D01*
G01X361000Y329773D02*
X361440Y330213D01*
G01D02*
X362640D01*
G01D02*
X363080Y329773D01*
G01D02*
X364280D01*
G01D02*
X364720Y330213D01*
G01D02*
X365920D01*
G01D02*
X366360Y329773D01*
G01D02*
X719455D01*
G01X361500Y338173D02*
X361940Y338613D01*
G01D02*
X363140D01*
G01D02*
X363580Y338173D01*
G01D02*
X364780D01*
G01D02*
X365220Y338613D01*
G01D02*
X366420D01*
G01D02*
X366860Y338173D01*
G01D02*
X368060D01*
G01D02*
X368500Y338613D01*
G01D02*
X369700D01*
G01D02*
X370140Y338173D01*
G01D02*
X371340D01*
G01D02*
X371780Y338613D01*
G01D02*
X372980D01*
G01D02*
X373420Y338173D01*
G01D02*
X705135D01*
G01X363800Y344573D02*
X364240Y345013D01*
G01D02*
X365440D01*
G01D02*
X365880Y344573D01*
G01D02*
X367080D01*
G01D02*
X367520Y345013D01*
G01D02*
X368720D01*
G01D02*
X369160Y344573D01*
G01D02*
X370360D01*
G01D02*
X370800Y345013D01*
G01D02*
X372000D01*
G01D02*
X372440Y344573D01*
G01D02*
X373640D01*
G01D02*
X374080Y345013D01*
G01D02*
X375280D01*
G01D02*
X375720Y344573D01*
G01D02*
X692769D01*
G01X555182Y505482D02*
X429475Y379775D01*
G01D02*
G02X426294Y378457I-3182J3182D01*
G01X430395Y378855D02*
G02X426293Y377157I-4101J4103D01*
G01X421015Y383793D02*
G03X423277Y384731I-1J3200D01*
G01D02*
X565589Y527043D01*
G01X421015Y382493D02*
G03X424197Y383811I0J4500D01*
G01D02*
X611273Y570887D01*
G01X362700Y352200D02*
X363140Y352640D01*
G01D02*
X364340D01*
G01D02*
X364780Y352200D01*
G01D02*
X365980D01*
G01D02*
X366420Y352640D01*
G01D02*
X367620D01*
G01D02*
X368060Y352200D01*
G01D02*
X369260D01*
G01D02*
X369700Y352640D01*
G01D02*
X370900D01*
G01D02*
X371340Y352200D01*
G01D02*
X372540D01*
G01D02*
X372980Y352640D01*
G01D02*
X374180D01*
G01D02*
X374620Y352200D01*
G01D02*
X681499D01*
G01X360300Y360187D02*
X360740Y359747D01*
G01D02*
X361940D01*
G01D02*
X362380Y360187D01*
G01D02*
X363630D01*
G01D02*
X364070Y359747D01*
G01D02*
X365297D01*
G01D02*
X365700Y360150D01*
G01D02*
X366947D01*
G01D02*
X367350Y359747D01*
G01D02*
X671649D01*
G01X429157Y374720D02*
G03X432338Y376038I-1J4500D01*
G01X429156Y373420D02*
G03X433258Y375118I1J5801D01*
G01X769865Y636497D02*
X360700D01*
G01D02*
X360297Y636900D01*
G01X433585Y365649D02*
G03X435847Y366587I-1J3200D01*
G01D02*
X526363Y457103D01*
G01X433585Y364349D02*
G03X436767Y365667I0J4500D01*
G01D02*
X527283Y456183D01*
G01X431384Y370948D02*
G03X434566Y372266I0J4500D01*
G01D02*
X535433Y473133D01*
G01X431384Y369648D02*
G03X435486Y371346I1J5801D01*
G01D02*
X536353Y472213D01*
G01X556102Y504562D02*
X430395Y378855D01*
G01X432338Y376038D02*
X554902Y498602D01*
G01X433258Y375118D02*
X555822Y497682D01*
G01X526363Y457103D02*
G02X530465Y458801I4101J-4103D01*
G01D02*
X659400D01*
G01X527283Y456183D02*
G02X530465Y457501I3182J-3182D01*
G01D02*
X660749D01*
G01X535433Y473133D02*
G02X538615Y474451I3182J-3182D01*
G01D02*
X556107D01*
G01D02*
X556555Y474900D01*
G01D02*
X557755D01*
G01D02*
X558203Y474451D01*
G01D02*
X559403D01*
G01D02*
X559851Y474900D01*
G01D02*
X561051D01*
G01D02*
X561499Y474451D01*
G01D02*
X562699D01*
G01D02*
X563147Y474900D01*
G01D02*
X564347D01*
G01D02*
X564795Y474451D01*
G01D02*
X565995D01*
G01D02*
X566443Y474900D01*
G01D02*
X567643D01*
G01D02*
X568091Y474451D01*
G01D02*
X569291D01*
G01D02*
X569739Y474900D01*
G01D02*
X570939D01*
G01D02*
X571387Y474451D01*
G01X536353Y472213D02*
G02X538615Y473151I2263J-2262D01*
G01D02*
X645546D01*
G01X571475Y506800D02*
X570275D01*
G01D02*
X569835Y507240D01*
G01D02*
X568635D01*
G01D02*
X568195Y506800D01*
G01D02*
X558363D01*
G01D02*
G03X555182Y505482I1J-4500D01*
G01X714364Y505500D02*
X558364D01*
G01D02*
G03X556102Y504562I1J-3200D01*
G01X565589Y527043D02*
Y527666D01*
G01D02*
X566438Y528514D01*
G01D02*
X567060D01*
G01D02*
X567909Y529363D01*
G01D02*
Y529985D01*
G01D02*
X568757Y530833D01*
G01D02*
X569379D01*
G01D02*
X570228Y531682D01*
G01D02*
Y532304D01*
G01D02*
X571076Y533153D01*
G01X554902Y498602D02*
G02X559004Y500300I4101J-4103D01*
G01D02*
X565780D01*
G01D02*
X566220Y500740D01*
G01D02*
X567420D01*
G01D02*
X567860Y500300D01*
G01D02*
X569060D01*
G01D02*
X569500Y500740D01*
G01D02*
X570700D01*
G01D02*
X571140Y500300D01*
G01X555822Y497682D02*
G02X559004Y499000I3182J-3182D01*
G01D02*
X732164D01*
G01X571387Y474451D02*
X643900D01*
G01X641595Y507240D02*
X640395D01*
G01D02*
X639955Y506800D01*
G01D02*
X638755D01*
G01D02*
X638315Y507240D01*
G01D02*
X637115D01*
G01D02*
X636675Y506800D01*
G01D02*
X635475D01*
G01D02*
X635035Y507240D01*
G01D02*
X633835D01*
G01D02*
X633395Y506800D01*
G01D02*
X583395D01*
G01D02*
X582955Y507240D01*
G01D02*
X581755D01*
G01D02*
X581315Y506800D01*
G01D02*
X580115D01*
G01D02*
X579675Y507240D01*
G01D02*
X578475D01*
G01D02*
X578035Y506800D01*
G01D02*
X576835D01*
G01D02*
X576395Y507240D01*
G01D02*
X575195D01*
G01D02*
X574755Y506800D01*
G01D02*
X573555D01*
G01D02*
X573115Y507240D01*
G01D02*
X571915D01*
G01D02*
X571475Y506800D01*
G01X571076Y533153D02*
X571699D01*
G01D02*
X572547Y534001D01*
G01D02*
Y534623D01*
G01D02*
X573396Y535472D01*
G01D02*
X574018D01*
G01D02*
X610353Y571807D01*
G01X571140Y500300D02*
X572340D01*
G01D02*
X572780Y500740D01*
G01D02*
X573980D01*
G01D02*
X574420Y500300D01*
G01D02*
X575620D01*
G01D02*
X576060Y500740D01*
G01D02*
X577260D01*
G01D02*
X577700Y500300D01*
G01D02*
X627700D01*
G01D02*
X628140Y500740D01*
G01D02*
X629340D01*
G01D02*
X629780Y500300D01*
G01D02*
X630980D01*
G01D02*
X631420Y500740D01*
G01D02*
X632620D01*
G01D02*
X633060Y500300D01*
G01D02*
X634260D01*
G01D02*
X634700Y500740D01*
G01D02*
X635900D01*
G01D02*
X636340Y500300D01*
G01D02*
X637540D01*
G01D02*
X637980Y500740D01*
G01D02*
X639180D01*
G01D02*
X639620Y500300D01*
G01D02*
X640820D01*
G01D02*
X641260Y500740D01*
G01D02*
X642460D01*
G01X610353Y571807D02*
G02X614455Y573505I4101J-4103D01*
G01D02*
X622780D01*
G01D02*
X623220Y573945D01*
G01D02*
X624420D01*
G01D02*
X624860Y573505D01*
G01D02*
X626060D01*
G01D02*
X626500Y573945D01*
G01D02*
X627700D01*
G01D02*
X628140Y573505D01*
G01D02*
X629340D01*
G01D02*
X629780Y573945D01*
G01D02*
X630980D01*
G01D02*
X631420Y573505D01*
G01D02*
X632620D01*
G01D02*
X633060Y573945D01*
G01D02*
X634260D01*
G01D02*
X634700Y573505D01*
G01D02*
X684700D01*
G01X611273Y570887D02*
G02X614455Y572205I3182J-3182D01*
G01D02*
X770412D01*
G01X705135Y338173D02*
G03X707397Y339111I-1J3200D01*
G01D02*
X758990Y390704D01*
G01X705136Y336873D02*
G03X708317Y338191I-1J4500D01*
G01D02*
X759910Y389784D01*
G01X692769Y344573D02*
G03X695031Y345511I-1J3200D01*
G01X692770Y343273D02*
G03X695951Y344591I-1J4500D01*
G01D02*
X756894Y405534D01*
G01X695031Y345511D02*
X755974Y406454D01*
G01X681499Y352200D02*
G03X683761Y353138I-1J3200D01*
G01D02*
X752825Y422202D01*
G01X681499Y350900D02*
G03X684681Y352218I0J4500D01*
G01D02*
X753745Y421282D01*
G01X671649Y359747D02*
G03X674830Y361065I-1J4500D01*
G01D02*
X752094Y438329D01*
G01X671650Y358447D02*
G03X675750Y360145I-1J5801D01*
G01D02*
X753014Y437409D01*
G01X659400Y458801D02*
G03X661230Y459559I0J2588D01*
G01D02*
X661760Y460089D01*
G01X660749Y457501D02*
G02X662166Y456914I0J-2004D01*
G01X643900Y474451D02*
G03X644373Y474507I1J2018D01*
G01D02*
G03X645327Y475042I-473J1962D01*
G01D02*
X646246Y475961D01*
G01X645546Y473151D02*
G02X646794Y472634I0J-1765D01*
G01X662604Y463284D02*
X665393Y460495D01*
G01D02*
G03X667955I1281J1281D01*
G01D02*
X668217Y460757D01*
G01D02*
G02X670551Y461723I2333J-2334D01*
G01D02*
X684718D01*
G01D02*
G03X685242Y461940I0J741D01*
G01D02*
G02X685818Y462083I575J-1086D01*
G01D02*
X687858D01*
G01X667745Y456089D02*
Y457617D01*
G01D02*
G02X668331Y459031I1999J0D01*
G01D02*
X669137Y459837D01*
G01D02*
G02X670551Y460423I1414J-1413D01*
G01D02*
X684805D01*
G01D02*
G02X685261Y460234I0J-645D01*
G01D02*
G03X685749Y460114I489J935D01*
G01D02*
X687858D01*
G01Y473894D02*
X668434D01*
G01D02*
G02X667940Y474100I1J698D01*
G01D02*
X666192Y475848D01*
G01D02*
G03X663858Y476814I-2333J-2334D01*
G01D02*
X651917D01*
G01D02*
G02X646251Y479161I0J8013D01*
G01X650837Y472421D02*
Y473533D01*
G01D02*
G02X651415Y474928I1973J0D01*
G01D02*
G02X652829Y475514I1414J-1413D01*
G01D02*
X663858D01*
G01D02*
G02X665272Y474928I0J-1999D01*
G01D02*
X667020Y473180D01*
G01D02*
G03X668434Y472594I1414J1413D01*
G01D02*
X684703D01*
G01D02*
G02X685556Y472240I-1J-1207D01*
G01D02*
X685593Y472204D01*
G01D02*
G03X686264Y471926I671J671D01*
G01D02*
X687858D01*
G01X671145Y454348D02*
Y452831D01*
G01D02*
G03X671800Y451250I2236J0D01*
G01D02*
G03X673900I1050J1050D01*
G01D02*
G03X674200Y451974I-724J724D01*
G01D02*
Y453939D01*
G01D02*
G02X674950Y455750I2561J0D01*
G01D02*
X675300Y456100D01*
G01D02*
G02X679431Y457811I4131J-4131D01*
G01D02*
X684363D01*
G01D02*
G03X684768Y457978I1J572D01*
G01D02*
X684818Y458028D01*
G01D02*
G02X685101Y458146I284J-282D01*
G01D02*
X687858D01*
G01X675745Y448189D02*
G02X675500Y448780I590J591D01*
G01D02*
Y453940D01*
G01D02*
X675501Y453939D01*
G01D02*
G02X675870Y454830I1260J0D01*
G01D02*
X676220Y455180D01*
G01D02*
G02X679431Y456511I3212J-3210D01*
G01D02*
X684353D01*
G01D02*
G02X684756Y456344I0J-570D01*
G01D02*
G03X685159Y456177I403J403D01*
G01D02*
X687858D01*
G01Y469957D02*
X686315D01*
G01D02*
G02X685108Y470457I0J1707D01*
G01D02*
G03X683500Y471123I-1608J-1608D01*
G01D02*
X660387D01*
G01D02*
G03X658760Y470450I-1J-2300D01*
G01D02*
X658230Y469920D01*
G01D02*
G02X657095Y469450I-1135J1135D01*
G01D02*
X654915D01*
G01D02*
G02X653351Y470098I0J2212D01*
G01X658195Y464248D02*
Y467631D01*
G01D02*
G02X658488Y468338I1000J0D01*
G01D02*
X659680Y469530D01*
G01D02*
G02X660387Y469823I707J-706D01*
G01D02*
X683500D01*
G01D02*
G02X684188Y469538I0J-973D01*
G01D02*
X685207Y468519D01*
G01D02*
G03X686487Y467989I1280J1280D01*
G01D02*
X687858D01*
G01X722072Y461814D02*
X704700D01*
G01D02*
G02X704205Y462019I0J700D01*
G01D02*
G03X703868Y462083I-337J-854D01*
G01D02*
X701858D01*
G01X722072Y460514D02*
X704846D01*
G01D02*
G03X704315Y460294I0J-751D01*
G01D02*
G02X703637Y460114I-678J1186D01*
G01D02*
X701858D01*
G01Y473894D02*
X725901D01*
G01Y472594D02*
X705184D01*
G01D02*
G03X704363Y472254I0J-1161D01*
G01D02*
G02X703571Y471926I-792J792D01*
G01D02*
X701858D01*
G01X714725Y457772D02*
X704792D01*
G01D02*
G02X704341Y457959I0J637D01*
G01D02*
G03X703890Y458146I-451J-450D01*
G01D02*
X701858D01*
G01X714725Y456472D02*
X704566D01*
G01D02*
G03X704283Y456354I1J-400D01*
G01D02*
X704253Y456324D01*
G01D02*
G02X703896Y456177I-356J357D01*
G01D02*
X701858D01*
G01X728501Y470921D02*
X707755D01*
G01D02*
G03X705791Y470108I0J-2779D01*
G01D02*
X705790Y470107D01*
G01D02*
G02X705428Y469957I-362J362D01*
G01D02*
X701858D01*
G01X728501Y469621D02*
X707756D01*
G01D02*
G03X706711Y469188I0J-1478D01*
G01D02*
X706511Y468988D01*
G01D02*
G02X704099Y467989I-2412J2412D01*
G01D02*
X701858D01*
G01X714364Y506800D02*
X710515D01*
G01D02*
X710075Y507240D01*
G01D02*
X708875D01*
G01D02*
X708435Y506800D01*
G01D02*
X707235D01*
G01D02*
X706795Y507240D01*
G01D02*
X705595D01*
G01D02*
X705155Y506800D01*
G01D02*
X704000D01*
G01D02*
X703600Y507200D01*
G01D02*
X702200D01*
G01D02*
X701800Y506800D01*
G01D02*
X648595D01*
G01D02*
X648155Y507240D01*
G01D02*
X646955D01*
G01D02*
X646515Y506800D01*
G01D02*
X645315D01*
G01D02*
X644875Y507240D01*
G01D02*
X643675D01*
G01D02*
X643235Y506800D01*
G01D02*
X642035D01*
G01D02*
X641595Y507240D01*
G01X642460Y500740D02*
X642900Y500300D01*
G01D02*
X692900D01*
G01D02*
X693340Y500740D01*
G01D02*
X694540D01*
G01D02*
X694980Y500300D01*
G01D02*
X696180D01*
G01D02*
X696620Y500740D01*
G01D02*
X697820D01*
G01D02*
X698260Y500300D01*
G01D02*
X699460D01*
G01D02*
X699900Y500740D01*
G01D02*
X701100D01*
G01D02*
X701540Y500300D01*
G01D02*
X702740D01*
G01D02*
X703180Y500740D01*
G01D02*
X704380D01*
G01D02*
X704820Y500300D01*
G01D02*
X732164D01*
G01X684700Y573505D02*
X685140Y573945D01*
G01D02*
X686340D01*
G01D02*
X686780Y573505D01*
G01D02*
X687980D01*
G01D02*
X688420Y573945D01*
G01D02*
X689620D01*
G01D02*
X690060Y573505D01*
G01D02*
X691260D01*
G01D02*
X691700Y573945D01*
G01D02*
X692900D01*
G01D02*
X693340Y573505D01*
G01D02*
X694540D01*
G01D02*
X694980Y573945D01*
G01D02*
X696180D01*
G01D02*
X696620Y573505D01*
G01D02*
X697820D01*
G01D02*
X698260Y573945D01*
G01D02*
X699460D01*
G01D02*
X699900Y573505D01*
G01D02*
X749900D01*
G01X781514Y338605D02*
X772561D01*
G01D02*
G03X771100Y338000I0J-2066D01*
G01D02*
G02X769789Y337457I-1311J1311D01*
G01D02*
X764680D01*
G01D02*
G03X758601Y334939I0J-8597D01*
G01D02*
X742085Y318423D01*
G01D02*
G02X738903Y317105I-3182J3182D01*
G01X781514Y334665D02*
X773699D01*
G01D02*
G02X771200Y335700I0J3534D01*
G01D02*
G03X770097Y336157I-1103J-1103D01*
G01D02*
X764683D01*
G01D02*
G03X759521Y334019I0J-7300D01*
G01D02*
X743005Y317503D01*
G01D02*
G02X738903Y315805I-4101J4103D01*
G01X730651Y323773D02*
G03X732913Y324711I-1J3200D01*
G01D02*
X759536Y351334D01*
G01X730652Y322473D02*
G03X733833Y323791I-1J4500D01*
G01D02*
X760456Y350414D01*
G01X719455Y329773D02*
G03X721717Y330711I-1J3200D01*
G01D02*
X758017Y367011D01*
G01X719456Y328473D02*
G03X722637Y329791I-1J4500D01*
G01D02*
X758937Y366091D01*
G01X759536Y351334D02*
G02X763638Y353032I4101J-4103D01*
G01D02*
X770065D01*
G01D02*
G03X772281Y353950I0J3134D01*
G01D02*
G02X773247Y354350I966J-966D01*
G01D02*
X781514D01*
G01X760456Y350414D02*
G02X763638Y351732I3182J-3182D01*
G01D02*
X770300D01*
G01D02*
G02X772117Y350980I1J-2569D01*
G01D02*
G03X773481Y350415I1364J1364D01*
G01D02*
X781514D01*
G01X758017Y367011D02*
G02X762119Y368709I4101J-4103D01*
G01D02*
X770090D01*
G01D02*
G03X771488Y369288I1J1975D01*
G01D02*
X771604Y369405D01*
G01D02*
G02X773284Y370100I1679J-1680D01*
G01D02*
X781514D01*
G01X758937Y366091D02*
G02X762119Y367409I3182J-3182D01*
G01D02*
X770817D01*
G01D02*
G02X772154Y366855I0J-1891D01*
G01D02*
G03X773820Y366165I1666J1666D01*
G01D02*
X781514D01*
G01X758990Y390704D02*
G02X763092Y392402I4101J-4103D01*
G01D02*
X770324D01*
G01D02*
G03X771648Y392951I0J1871D01*
G01D02*
X771649D01*
G01D02*
X772007Y393308D01*
G01D02*
G02X773000Y393720I994J-993D01*
G01D02*
X781514D01*
G01X759910Y389784D02*
G02X763092Y391102I3182J-3182D01*
G01D02*
X770204D01*
G01D02*
G02X770938Y390798I0J-1038D01*
G01D02*
X771010Y390726D01*
G01D02*
G02X771357Y390443I-1240J-1874D01*
G01D02*
G03X772946Y389785I1589J1589D01*
G01D02*
X781514D01*
G01X755974Y406454D02*
G02X760076Y408152I4101J-4103D01*
G01D02*
X770828D01*
G01D02*
G03X772185Y408714I0J1919D01*
G01D02*
G02X774010Y409470I1825J-1825D01*
G01D02*
X781514D01*
G01X756894Y405534D02*
G02X760076Y406852I3182J-3182D01*
G01D02*
X770417D01*
G01D02*
G02X772006Y406194I0J-2248D01*
G01D02*
G03X773596Y405535I1590J1589D01*
G01D02*
X781514D01*
G01X735231Y457167D02*
X735685Y456713D01*
G01D02*
G03X738867Y455395I3182J3182D01*
G01D02*
X770162D01*
G01D02*
G03X771755Y456055I0J2252D01*
G01D02*
G02X773348Y456715I1593J-1592D01*
G01D02*
X781514D01*
G01X735191Y453967D02*
G02X735500Y454095I309J-309D01*
G01D02*
X770072D01*
G01D02*
G02X771665Y453435I0J-2252D01*
G01D02*
G03X773258Y452775I1593J1592D01*
G01D02*
X781514D01*
G01X746845Y476389D02*
X747410Y475823D01*
G01D02*
G03X748776Y475258I1365J1366D01*
G01D02*
X754497D01*
G01D02*
G02X757679Y473940I0J-4500D01*
G01D02*
X759159Y472460D01*
G01D02*
G03X762341Y471142I3182J3182D01*
G01D02*
X770610D01*
G01D02*
G03X772201Y471801I0J2250D01*
G01D02*
G02X773792Y472460I1591J-1591D01*
G01D02*
X781514D01*
G01X746845Y473189D02*
G02X748702Y473958I1857J-1857D01*
G01D02*
X754497D01*
G01D02*
G02X756759Y473020I-1J-3200D01*
G01D02*
X758239Y471540D01*
G01D02*
G03X762341Y469842I4101J4103D01*
G01D02*
X770792D01*
G01D02*
G02X772100Y469300I0J-1849D01*
G01D02*
X772216Y469183D01*
G01D02*
G03X773806Y468525I1589J1590D01*
G01D02*
X781514D01*
G01X752825Y422202D02*
G02X756927Y423900I4101J-4103D01*
G01D02*
X770281D01*
G01D02*
G03X771850Y424550I0J2219D01*
G01D02*
G02X773468Y425220I1618J-1618D01*
G01D02*
X781514D01*
G01X753745Y421282D02*
G02X756927Y422600I3182J-3182D01*
G01D02*
X770381D01*
G01D02*
G02X771950Y421950I0J-2219D01*
G01D02*
X772150Y421750D01*
G01D02*
G03X773285Y421280I1135J1135D01*
G01D02*
X781514D01*
G01X752094Y438329D02*
G02X755276Y439647I3182J-3182D01*
G01D02*
X771355D01*
G01D02*
G03X772272Y440027I0J1297D01*
G01D02*
G02X774537Y440965I2265J-2265D01*
G01D02*
X781514D01*
G01X753014Y437409D02*
G02X755276Y438347I2263J-2262D01*
G01D02*
X771502D01*
G01D02*
G02X772523Y437924I0J-1444D01*
G01D02*
G03X774681Y437030I2158J2158D01*
G01D02*
X781514D01*
G01X744956Y486704D02*
G03X747644Y485592I2687J2690D01*
G01D02*
X770677D01*
G01D02*
G02X772267Y484934I1J-2248D01*
G01D02*
X772383Y484817D01*
G01D02*
G03X773691Y484275I1308J1307D01*
G01D02*
X781514D01*
G01X726589Y460909D02*
X724406D01*
G01D02*
G02X723625Y461212I0J1158D01*
G01D02*
G03X722072Y461814I-1551J-1698D01*
G01X721445Y455789D02*
X721692D01*
G01D02*
G03X723650Y456600I0J2769D01*
G01D02*
G03X723900Y457204I-605J604D01*
G01D02*
Y458686D01*
G01D02*
G03X723607Y459393I-999J0D01*
G01D02*
X722779Y460221D01*
G01D02*
G03X722072Y460514I-707J-706D01*
G01X725901Y473894D02*
G03X728023Y474773I0J3001D01*
G01D02*
X730668Y477418D01*
G01D02*
G02X732790Y478297I2122J-2122D01*
G01D02*
X743520D01*
G01X738745Y472789D02*
G03X739588Y473138I0J1193D01*
G01D02*
X740148Y473698D01*
G01D02*
G03X740822Y475325I-1627J1627D01*
G01D02*
Y475770D01*
G01D02*
G03X740462Y476638I-1226J0D01*
G01D02*
G03X739595Y476997I-867J-867D01*
G01D02*
X732790D01*
G01D02*
G03X731588Y476498I1J-1700D01*
G01D02*
X728943Y473853D01*
G01D02*
G02X725901Y472594I-3041J3042D01*
G01X717993Y451389D02*
G02X717593Y452355I966J966D01*
G01D02*
Y454740D01*
G01D02*
G03X716707Y456882I-3033J0D01*
G01D02*
X716591Y456998D01*
G01D02*
G03X714725Y457772I-1865J-1859D01*
G01X713845Y447289D02*
X714750D01*
G01D02*
G03X715841Y447741I0J1543D01*
G01D02*
G03X716293Y448832I-1091J1091D01*
G01D02*
Y454739D01*
G01D02*
G03X715785Y455964I-1732J-1D01*
G01D02*
X715669Y456081D01*
G01D02*
G03X714725Y456472I-943J-942D01*
G01X735259Y469898D02*
X734942Y469582D01*
G01D02*
G02X733688Y469062I-1255J1254D01*
G01D02*
G02X733450Y469050I-236J2308D01*
G01D02*
X732299D01*
G01D02*
G02X732130Y469060I-5J1349D01*
G01D02*
G02X731345Y469445I170J1339D01*
G01D02*
X730835Y469955D01*
G01D02*
G03X728501Y470921I-2333J-2334D01*
G01X731751Y464398D02*
Y466564D01*
G01D02*
G03X731302Y467648I-1533J0D01*
G01D02*
X729915Y469035D01*
G01D02*
G03X728501Y469621I-1414J-1413D01*
G01X781514Y543330D02*
X774161D01*
G01D02*
G03X772116Y542483I0J-2892D01*
G01D02*
G02X770629Y541867I-1487J1487D01*
G01D02*
X765300D01*
G01D02*
X764860Y542307D01*
G01D02*
X763660D01*
G01D02*
X763220Y541867D01*
G01D02*
X762020D01*
G01D02*
X761580Y542307D01*
G01D02*
X760380D01*
G01D02*
X759940Y541867D01*
G01D02*
X758740D01*
G01D02*
X758300Y542307D01*
G01D02*
X757100D01*
G01D02*
X756660Y541867D01*
G01D02*
X755460D01*
G01D02*
X755020Y542307D01*
G01D02*
X753820D01*
G01D02*
X753380Y541867D01*
G01D02*
X751503D01*
G01D02*
G03X749735Y541135I0J-2501D01*
G01D02*
X716132Y507532D01*
G01D02*
G02X714364Y506800I-1768J1769D01*
G01X781514Y539390D02*
X773542D01*
G01D02*
G02X772122Y539978I0J2009D01*
G01D02*
G03X770701Y540567I-1421J-1420D01*
G01D02*
X751503D01*
G01D02*
G03X750655Y540215I1J-1201D01*
G01D02*
X717052Y506612D01*
G01D02*
G02X714364Y505500I-2687J2690D01*
G01X732164Y500300D02*
G02X733932Y499568I0J-2501D01*
G01D02*
X745876Y487624D01*
G01D02*
G03X747644Y486892I1768J1769D01*
G01D02*
X752680D01*
G01D02*
X753120Y487332D01*
G01D02*
X754320D01*
G01D02*
X754760Y486892D01*
G01D02*
X755960D01*
G01D02*
X756400Y487332D01*
G01D02*
X757600D01*
G01D02*
X758040Y486892D01*
G01D02*
X759240D01*
G01D02*
X759680Y487332D01*
G01D02*
X760880D01*
G01D02*
X761320Y486892D01*
G01D02*
X762520D01*
G01D02*
X762960Y487332D01*
G01D02*
X764160D01*
G01D02*
X764600Y486892D01*
G01D02*
X771570D01*
G01D02*
G03X772304Y487196I0J1038D01*
G01D02*
G02X774752Y488210I2448J-2448D01*
G01D02*
X781514D01*
G01X732164Y499000D02*
G02X733012Y498648I-1J-1201D01*
G01D02*
X744956Y486704D01*
G01X749900Y573505D02*
X750340Y573945D01*
G01D02*
X751540D01*
G01D02*
X751980Y573505D01*
G01D02*
X753180D01*
G01D02*
X753620Y573945D01*
G01D02*
X754820D01*
G01D02*
X755260Y573505D01*
G01D02*
X756460D01*
G01D02*
X756900Y573945D01*
G01D02*
X758100D01*
G01D02*
X758540Y573505D01*
G01D02*
X759740D01*
G01D02*
X760180Y573945D01*
G01D02*
X761380D01*
G01D02*
X761820Y573505D01*
G01D02*
X770488D01*
G01D02*
G03X771261Y573825I0J1093D01*
G01D02*
G02X774089Y574825I2828J-3499D01*
G01D02*
X781514D01*
G01X770412Y572205D02*
G02X771322Y571828I0J-1287D01*
G01D02*
G03X774079Y570885I2756J3557D01*
G01D02*
X781514D01*
G01X747523Y597313D02*
G02X750705Y595995I0J-4500D01*
G01D02*
X756079Y590621D01*
G01D02*
G03X759261Y589303I3182J3182D01*
G01D02*
X769517D01*
G01D02*
G03X771200Y590000I0J2380D01*
G01D02*
G02X772588Y590575I1388J-1388D01*
G01D02*
X781514D01*
G01X747523Y596013D02*
G02X749785Y595075I-1J-3200D01*
G01D02*
X755159Y589701D01*
G01D02*
G03X759261Y588003I4101J4103D01*
G01D02*
X769516D01*
G01D02*
G03X769521I2J3681D01*
G01D02*
X769961D01*
G01D02*
G02X771900Y587200I0J-2742D01*
G01D02*
G03X773264Y586635I1364J1364D01*
G01D02*
X781514D01*
G01X768722Y603685D02*
G03X771902Y605002I0J4498D01*
G01D02*
G02X775084Y606320I3182J-3182D01*
G01D02*
X781514D01*
G01X769634Y620350D02*
G03X771710Y621210I0J2936D01*
G01D02*
G02X773786Y622070I2076J-2076D01*
G01D02*
X781514D01*
G01X770099Y619050D02*
G02X771210Y618590I0J-1572D01*
G01D02*
G03X772321Y618130I1111J1112D01*
G01D02*
X781514D01*
G01Y637815D02*
X773047D01*
G01D02*
G03X771456Y637156I0J-2250D01*
G01D02*
G02X769865Y636497I-1591J1591D01*
G01X781514Y633880D02*
X772586D01*
G01D02*
G02X771278Y634422I0J1849D01*
G01D02*
X771162Y634539D01*
G01D02*
G03X769572Y635197I-1589J-1590D01*
G54D11*
G01X-1003937Y-3937D02*
G03X-1000000Y-7874I3937J0D01*
G01X-1031496Y-31496D02*
G03X-1027559Y-35433I3937J0D01*
G01X-986221Y-7874D02*
G03Y0I0J3937D01*
G01Y-7874D02*
X-1000000D01*
G01X-1027559Y-35433D02*
X791338D01*
G01X-1031496Y95866D02*
Y-31496D01*
G01X-996063Y3937D02*
G03X-992126Y0I3937J0D01*
G01X-996063Y39370D02*
G03X-1003937I-3937J0D01*
G01X-996063Y3937D02*
G03X-992126Y0I3937J0D01*
G01D02*
X-318898D01*
G01D02*
X-992126D01*
G01X-955512D02*
X-986221D01*
G01X-996063Y3937D02*
Y103740D01*
G01Y39370D02*
Y70079D01*
G01X-1003937Y-3937D02*
Y39370D01*
G01X-1027559Y99803D02*
G03X-1031496Y95866I0J-3937D01*
G01X-1003937D02*
G03X-1007874Y99803I-3937J0D01*
G01X-996063Y103740D02*
G03X-1000000Y107677I-3937J0D01*
G01X-1003937Y70079D02*
G03X-996063I3937J0D01*
G01X-1029528Y107677D02*
X-1000000D01*
G01X-1007874Y99803D02*
X-1027559D01*
G01X-1003937Y70079D02*
Y95866D01*
G01X-1031496Y109646D02*
X-1029528Y107677D01*
G01X-1031496Y109646D02*
Y134055D01*
G01X-1002166Y136024D02*
G03Y143504I0J3740D01*
G01X-1000000Y187599D02*
G03X-996063Y191536I0J3937D01*
G01X-1029528Y187599D02*
X-1000000D01*
G01X-1029528Y143504D02*
X-1002166D01*
G01X-1029528Y136024D02*
X-1002166D01*
G01X-1029528D02*
X-1031496Y134055D01*
G01X-1029528Y187599D02*
X-1031496Y185630D01*
G01Y145473D02*
X-1029528Y143504D01*
G01X-996063Y261221D02*
Y191536D01*
G01X-1031496Y145473D02*
Y185630D01*
G01X-996063Y261221D02*
G03X-1000000Y265158I-3937J0D01*
G01X-1029528D02*
X-1000000D01*
G01X-1031496Y267126D02*
X-1029528Y265158D01*
G01X-1031496Y267126D02*
Y543504D01*
G01X-1002166Y545473D02*
G03Y552953I0J3740D01*
G01X-1029528D02*
X-1002166D01*
G01X-1029528Y545473D02*
X-1002166D01*
G01X-1031496Y554922D02*
X-1029528Y552953D01*
G01Y545473D02*
X-1031496Y543504D01*
G01Y554922D02*
Y595079D01*
G01X-1007874Y604922D02*
G03X-1003937Y608859I0J3937D01*
G01X-1031496D02*
G03X-1027559Y604922I3937J0D01*
G01X-1000000Y597048D02*
G03X-996063Y600985I0J3937D01*
G01X-1027559Y604922D02*
X-1007874D01*
G01X-1029528Y597048D02*
X-1000000D01*
G01X-1029528D02*
X-1031496Y595079D01*
G01X-996063Y921260D02*
Y600985D01*
G01X-1003937Y608859D02*
Y708662D01*
G01X-1031496Y956693D02*
Y608859D01*
G01X-1003937Y739370D02*
G03X-996063I3937J0D01*
G01Y708662D02*
G03X-1003937I-3937J0D01*
G01X-996063D02*
Y739370D01*
G01X-1003937D02*
Y929134D01*
G01X-992126Y925197D02*
G03X-996063Y921260I0J-3937D01*
G01X-1000000Y933071D02*
G03X-1003937Y929134I0J-3937D01*
G01X-986221Y925197D02*
G03Y933071I0J3937D01*
G01X-1027559Y960630D02*
G03X-1031496Y956693I0J-3937D01*
G01X-992126Y925197D02*
G03X-996063Y921260I0J-3937D01*
G01X791338Y960630D02*
X-1027559D01*
G01X-1000000Y933071D02*
X-986221D01*
G01X-992126Y925197D02*
X-240158D01*
G01X-986221D02*
X-955512D01*
G01X-992126D02*
X-240158D01*
G01X-955512Y0D02*
G03Y-7874I0J-3937D01*
G01X-769685D02*
X-955512D01*
G01Y933071D02*
G03Y925197I0J-3937D01*
G01Y933071D02*
X-750000D01*
G01X-769685Y-7874D02*
G03Y0I0J3937D01*
G01X-738977D02*
X-769685D01*
G01X-738977D02*
G03Y-7874I0J-3937D01*
G01X-522835D02*
X-738977D01*
G01X-719292Y933071D02*
G03Y925197I0J-3937D01*
G01X-750000D02*
G03Y933071I0J3937D01*
G01X-719292D02*
X-512992D01*
G01X-750000Y925197D02*
X-719292D01*
G01X-574792Y-69796D02*
Y-81796D01*
G01X-577092Y-69796D02*
X-572492D01*
G01X-570492Y-81796D02*
Y-69796D01*
G01Y-75596D02*
X-569992Y-74596D01*
X-569492Y-73996D01*
X-568692Y-73796D01*
X-568092Y-73996D01*
X-567392Y-74796D01*
X-567092Y-75996D01*
Y-81796D01*
G01X-562792Y-73796D02*
Y-81796D01*
G01Y-70596D02*
X-562992Y-70396D01*
Y-69996D01*
X-562792Y-69796D01*
X-562592Y-69996D01*
Y-70396D01*
X-562792Y-70596D01*
G01X-558292Y-80396D02*
X-557792Y-81196D01*
X-557092Y-81796D01*
X-556492D01*
X-555892Y-81396D01*
X-555492Y-80796D01*
X-555292Y-79996D01*
X-555392Y-78796D01*
X-555792Y-78196D01*
X-557592Y-76996D01*
X-557992Y-75596D01*
X-557792Y-74596D01*
X-557392Y-73996D01*
X-556792Y-73796D01*
X-556192Y-73996D01*
X-555592Y-74596D01*
G01X-546192Y-84796D02*
X-545492Y-85596D01*
X-544692Y-85796D01*
X-543992Y-85596D01*
X-543392Y-84596D01*
X-542992Y-83196D01*
Y-73796D01*
G01Y-75396D02*
X-543392Y-74596D01*
X-543992Y-73996D01*
X-544692Y-73796D01*
X-545492Y-74196D01*
X-545992Y-74996D01*
X-546392Y-76396D01*
X-546592Y-77796D01*
X-546492Y-78996D01*
X-546092Y-80396D01*
X-545492Y-81396D01*
X-544692Y-81796D01*
X-544092Y-81596D01*
X-543392Y-80796D01*
X-542992Y-79996D01*
G01X-540292Y-76396D02*
X-537092D01*
X-537392Y-74996D01*
X-537892Y-74196D01*
X-538592Y-73796D01*
X-539292Y-73996D01*
X-539892Y-74596D01*
X-540292Y-75996D01*
X-540492Y-77196D01*
Y-78396D01*
X-540292Y-79596D01*
X-539792Y-80796D01*
X-539192Y-81596D01*
X-538492Y-81796D01*
X-537792Y-81396D01*
X-537092Y-80196D01*
G01X-534192Y-81796D02*
Y-73796D01*
G01Y-75396D02*
X-533692Y-74596D01*
X-533192Y-73996D01*
X-532492Y-73796D01*
X-531992Y-73996D01*
X-531392Y-74596D01*
G01X-528592Y-81796D02*
Y-69796D01*
G01Y-75796D02*
X-528092Y-74596D01*
X-527492Y-73996D01*
X-526892Y-73796D01*
X-525992Y-74196D01*
X-525392Y-74996D01*
X-524992Y-76396D01*
Y-77996D01*
X-525192Y-79596D01*
X-525592Y-80796D01*
X-526292Y-81596D01*
X-526892Y-81796D01*
X-527492Y-81596D01*
X-528092Y-80996D01*
X-528592Y-79996D01*
G01X-522292Y-76396D02*
X-519092D01*
X-519392Y-74996D01*
X-519892Y-74196D01*
X-520592Y-73796D01*
X-521292Y-73996D01*
X-521892Y-74596D01*
X-522292Y-75996D01*
X-522492Y-77196D01*
Y-78396D01*
X-522292Y-79596D01*
X-521792Y-80796D01*
X-521192Y-81596D01*
X-520492Y-81796D01*
X-519792Y-81396D01*
X-519092Y-80196D01*
G01X-516192Y-81796D02*
Y-73796D01*
G01Y-75396D02*
X-515692Y-74596D01*
X-515192Y-73996D01*
X-514492Y-73796D01*
X-513992Y-73996D01*
X-513392Y-74596D01*
G01X-502792Y-73796D02*
Y-81796D01*
G01Y-70596D02*
X-502992Y-70396D01*
Y-69996D01*
X-502792Y-69796D01*
X-502592Y-69996D01*
Y-70396D01*
X-502792Y-70596D01*
G01X-498292Y-80396D02*
X-497792Y-81196D01*
X-497092Y-81796D01*
X-496492D01*
X-495892Y-81396D01*
X-495492Y-80796D01*
X-495292Y-79996D01*
X-495392Y-78796D01*
X-495792Y-78196D01*
X-497592Y-76996D01*
X-497992Y-75596D01*
X-497792Y-74596D01*
X-497392Y-73996D01*
X-496792Y-73796D01*
X-496192Y-73996D01*
X-495592Y-74596D01*
G01X-486392Y-84796D02*
X-485692Y-85596D01*
X-485092Y-85796D01*
X-484292Y-85396D01*
X-483692Y-84396D01*
X-483392Y-82596D01*
Y-73796D01*
G01Y-70596D02*
X-483592Y-70396D01*
Y-69996D01*
X-483392Y-69796D01*
X-483192Y-69996D01*
Y-70396D01*
X-483392Y-70596D01*
G01X-480492Y-73796D02*
Y-79396D01*
X-480092Y-80796D01*
X-479492Y-81596D01*
X-478792Y-81796D01*
X-478092Y-81596D01*
X-477492Y-80796D01*
X-477092Y-79396D01*
G01Y-81796D02*
Y-73796D01*
G01X-474292Y-80396D02*
X-473792Y-81196D01*
X-473092Y-81796D01*
X-472492D01*
X-471892Y-81396D01*
X-471492Y-80796D01*
X-471292Y-79996D01*
X-471392Y-78796D01*
X-471792Y-78196D01*
X-473592Y-76996D01*
X-473992Y-75596D01*
X-473792Y-74596D01*
X-473392Y-73996D01*
X-472792Y-73796D01*
X-472192Y-73996D01*
X-471592Y-74596D01*
G01X-466792Y-69796D02*
Y-81796D01*
G01X-468192Y-73796D02*
X-465392D01*
G01X-455392Y-81796D02*
Y-71596D01*
X-455192Y-70596D01*
X-454792Y-69996D01*
X-454192Y-69796D01*
X-453592Y-70196D01*
X-453292Y-71196D01*
G01X-454492Y-74596D02*
X-456492D01*
G01X-448792Y-81796D02*
X-449392Y-81596D01*
X-449992Y-80796D01*
X-450392Y-79396D01*
X-450592Y-77796D01*
X-450392Y-76196D01*
X-449992Y-74796D01*
X-449392Y-73996D01*
X-448792Y-73796D01*
X-448192Y-73996D01*
X-447592Y-74796D01*
X-447192Y-76196D01*
X-447092Y-77796D01*
X-447192Y-79396D01*
X-447592Y-80796D01*
X-448192Y-81596D01*
X-448792Y-81796D01*
G01X-444192D02*
Y-73796D01*
G01Y-75396D02*
X-443692Y-74596D01*
X-443192Y-73996D01*
X-442492Y-73796D01*
X-441992Y-73996D01*
X-441392Y-74596D01*
G01X-432892Y-85396D02*
X-432292Y-85796D01*
X-431492Y-85396D01*
X-430992Y-84596D01*
X-430592Y-83596D01*
X-429992Y-80396D01*
X-428692Y-73796D01*
G01X-431892D02*
X-429992Y-80396D01*
G01X-424792Y-81796D02*
X-425392Y-81596D01*
X-425992Y-80796D01*
X-426392Y-79396D01*
X-426592Y-77796D01*
X-426392Y-76196D01*
X-425992Y-74796D01*
X-425392Y-73996D01*
X-424792Y-73796D01*
X-424192Y-73996D01*
X-423592Y-74796D01*
X-423192Y-76196D01*
X-423092Y-77796D01*
X-423192Y-79396D01*
X-423592Y-80796D01*
X-424192Y-81596D01*
X-424792Y-81796D01*
G01X-420492Y-73796D02*
Y-79396D01*
X-420092Y-80796D01*
X-419492Y-81596D01*
X-418792Y-81796D01*
X-418092Y-81596D01*
X-417492Y-80796D01*
X-417092Y-79396D01*
G01Y-81796D02*
Y-73796D01*
G01X-408192Y-81796D02*
Y-73796D01*
G01Y-75396D02*
X-407692Y-74596D01*
X-407192Y-73996D01*
X-406492Y-73796D01*
X-405992Y-73996D01*
X-405392Y-74596D01*
G01X-402292Y-76396D02*
X-399092D01*
X-399392Y-74996D01*
X-399892Y-74196D01*
X-400592Y-73796D01*
X-401292Y-73996D01*
X-401892Y-74596D01*
X-402292Y-75996D01*
X-402492Y-77196D01*
Y-78396D01*
X-402292Y-79596D01*
X-401792Y-80796D01*
X-401192Y-81596D01*
X-400492Y-81796D01*
X-399792Y-81396D01*
X-399092Y-80196D01*
G01X-395392Y-81796D02*
Y-71596D01*
X-395192Y-70596D01*
X-394792Y-69996D01*
X-394192Y-69796D01*
X-393592Y-70196D01*
X-393292Y-71196D01*
G01X-394492Y-74596D02*
X-396492D01*
G01X-390292Y-76396D02*
X-387092D01*
X-387392Y-74996D01*
X-387892Y-74196D01*
X-388592Y-73796D01*
X-389292Y-73996D01*
X-389892Y-74596D01*
X-390292Y-75996D01*
X-390492Y-77196D01*
Y-78396D01*
X-390292Y-79596D01*
X-389792Y-80796D01*
X-389192Y-81596D01*
X-388492Y-81796D01*
X-387792Y-81396D01*
X-387092Y-80196D01*
G01X-384192Y-81796D02*
Y-73796D01*
G01Y-75396D02*
X-383692Y-74596D01*
X-383192Y-73996D01*
X-382492Y-73796D01*
X-381992Y-73996D01*
X-381392Y-74596D01*
G01X-378292Y-76396D02*
X-375092D01*
X-375392Y-74996D01*
X-375892Y-74196D01*
X-376592Y-73796D01*
X-377292Y-73996D01*
X-377892Y-74596D01*
X-378292Y-75996D01*
X-378492Y-77196D01*
Y-78396D01*
X-378292Y-79596D01*
X-377792Y-80796D01*
X-377192Y-81596D01*
X-376492Y-81796D01*
X-375792Y-81396D01*
X-375092Y-80196D01*
G01X-372492Y-81796D02*
Y-73796D01*
G01Y-75796D02*
X-372092Y-74796D01*
X-371492Y-73996D01*
X-370692Y-73796D01*
X-369992Y-73996D01*
X-369392Y-74796D01*
X-369092Y-76196D01*
Y-81796D01*
G01X-363192Y-74796D02*
X-363892Y-73996D01*
X-364492Y-73796D01*
X-365292Y-74196D01*
X-365892Y-74996D01*
X-366292Y-76396D01*
X-366392Y-77796D01*
X-366292Y-79196D01*
X-365892Y-80396D01*
X-365292Y-81396D01*
X-364492Y-81796D01*
X-363792Y-81396D01*
X-363192Y-80596D01*
G01X-360292Y-76396D02*
X-357092D01*
X-357392Y-74996D01*
X-357892Y-74196D01*
X-358592Y-73796D01*
X-359292Y-73996D01*
X-359892Y-74596D01*
X-360292Y-75996D01*
X-360492Y-77196D01*
Y-78396D01*
X-360292Y-79596D01*
X-359792Y-80796D01*
X-359192Y-81596D01*
X-358492Y-81796D01*
X-357792Y-81396D01*
X-357092Y-80196D01*
G01X-346792Y-69796D02*
Y-81796D01*
G01X-348192Y-73796D02*
X-345392D01*
G01X-340792Y-81796D02*
X-341392Y-81596D01*
X-341992Y-80796D01*
X-342392Y-79396D01*
X-342592Y-77796D01*
X-342392Y-76196D01*
X-341992Y-74796D01*
X-341392Y-73996D01*
X-340792Y-73796D01*
X-340192Y-73996D01*
X-339592Y-74796D01*
X-339192Y-76196D01*
X-339092Y-77796D01*
X-339192Y-79396D01*
X-339592Y-80796D01*
X-340192Y-81596D01*
X-340792Y-81796D01*
G01X-329392D02*
Y-71596D01*
X-329192Y-70596D01*
X-328792Y-69996D01*
X-328192Y-69796D01*
X-327592Y-70196D01*
X-327292Y-71196D01*
G01X-328492Y-74596D02*
X-330492D01*
G01X-322792Y-73796D02*
Y-81796D01*
G01Y-70596D02*
X-322992Y-70396D01*
Y-69996D01*
X-322792Y-69796D01*
X-322592Y-69996D01*
Y-70396D01*
X-322792Y-70596D01*
G01X-318492Y-81796D02*
Y-73796D01*
G01Y-75796D02*
X-318092Y-74796D01*
X-317492Y-73996D01*
X-316692Y-73796D01*
X-315992Y-73996D01*
X-315392Y-74796D01*
X-315092Y-76196D01*
Y-81796D01*
G01X-308992Y-69796D02*
Y-81796D01*
G01Y-79996D02*
X-309392Y-80996D01*
X-309992Y-81596D01*
X-310692Y-81796D01*
X-311492Y-81396D01*
X-312092Y-80396D01*
X-312492Y-79196D01*
X-312592Y-77796D01*
X-312492Y-76396D01*
X-312092Y-75196D01*
X-311492Y-74196D01*
X-310692Y-73796D01*
X-309992Y-73996D01*
X-309492Y-74396D01*
X-308992Y-75196D01*
G01X-298792Y-69796D02*
Y-81796D01*
G01X-300192Y-73796D02*
X-297392D01*
G01X-294492Y-81796D02*
Y-69796D01*
G01Y-75596D02*
X-293992Y-74596D01*
X-293492Y-73996D01*
X-292692Y-73796D01*
X-292092Y-73996D01*
X-291392Y-74796D01*
X-291092Y-75996D01*
Y-81796D01*
G01X-288292Y-76396D02*
X-285092D01*
X-285392Y-74996D01*
X-285892Y-74196D01*
X-286592Y-73796D01*
X-287292Y-73996D01*
X-287892Y-74596D01*
X-288292Y-75996D01*
X-288492Y-77196D01*
Y-78396D01*
X-288292Y-79596D01*
X-287792Y-80796D01*
X-287192Y-81596D01*
X-286492Y-81796D01*
X-285792Y-81396D01*
X-285092Y-80196D01*
G01X-272992Y-69796D02*
Y-81796D01*
G01Y-79996D02*
X-273392Y-80996D01*
X-273992Y-81596D01*
X-274692Y-81796D01*
X-275492Y-81396D01*
X-276092Y-80396D01*
X-276492Y-79196D01*
X-276592Y-77796D01*
X-276492Y-76396D01*
X-276092Y-75196D01*
X-275492Y-74196D01*
X-274692Y-73796D01*
X-273992Y-73996D01*
X-273492Y-74396D01*
X-272992Y-75196D01*
G01X-268792Y-73796D02*
Y-81796D01*
G01Y-70596D02*
X-268992Y-70396D01*
Y-69996D01*
X-268792Y-69796D01*
X-268592Y-69996D01*
Y-70396D01*
X-268792Y-70596D01*
G01X-263392Y-81796D02*
Y-71596D01*
X-263192Y-70596D01*
X-262792Y-69996D01*
X-262192Y-69796D01*
X-261592Y-70196D01*
X-261292Y-71196D01*
G01X-262492Y-74596D02*
X-264492D01*
G01X-257392Y-81796D02*
Y-71596D01*
X-257192Y-70596D01*
X-256792Y-69996D01*
X-256192Y-69796D01*
X-255592Y-70196D01*
X-255292Y-71196D01*
G01X-256492Y-74596D02*
X-258492D01*
G01X-252292Y-76396D02*
X-249092D01*
X-249392Y-74996D01*
X-249892Y-74196D01*
X-250592Y-73796D01*
X-251292Y-73996D01*
X-251892Y-74596D01*
X-252292Y-75996D01*
X-252492Y-77196D01*
Y-78396D01*
X-252292Y-79596D01*
X-251792Y-80796D01*
X-251192Y-81596D01*
X-250492Y-81796D01*
X-249792Y-81396D01*
X-249092Y-80196D01*
G01X-246192Y-81796D02*
Y-73796D01*
G01Y-75396D02*
X-245692Y-74596D01*
X-245192Y-73996D01*
X-244492Y-73796D01*
X-243992Y-73996D01*
X-243392Y-74596D01*
G01X-240292Y-76396D02*
X-237092D01*
X-237392Y-74996D01*
X-237892Y-74196D01*
X-238592Y-73796D01*
X-239292Y-73996D01*
X-239892Y-74596D01*
X-240292Y-75996D01*
X-240492Y-77196D01*
Y-78396D01*
X-240292Y-79596D01*
X-239792Y-80796D01*
X-239192Y-81596D01*
X-238492Y-81796D01*
X-237792Y-81396D01*
X-237092Y-80196D01*
G01X-234492Y-81796D02*
Y-73796D01*
G01Y-75796D02*
X-234092Y-74796D01*
X-233492Y-73996D01*
X-232692Y-73796D01*
X-231992Y-73996D01*
X-231392Y-74796D01*
X-231092Y-76196D01*
Y-81796D01*
G01X-226792Y-69796D02*
Y-81796D01*
G01X-228192Y-73796D02*
X-225392D01*
G01X-220792D02*
Y-81796D01*
G01Y-70596D02*
X-220992Y-70396D01*
Y-69996D01*
X-220792Y-69796D01*
X-220592Y-69996D01*
Y-70396D01*
X-220792Y-70596D01*
G01X-212992Y-81796D02*
Y-73796D01*
G01Y-75196D02*
X-213392Y-74396D01*
X-213992Y-73996D01*
X-214692Y-73796D01*
X-215392Y-74196D01*
X-215992Y-74996D01*
X-216392Y-76196D01*
X-216592Y-77796D01*
X-216392Y-79396D01*
X-215992Y-80596D01*
X-215392Y-81396D01*
X-214692Y-81796D01*
X-213992Y-81596D01*
X-213392Y-80996D01*
X-212992Y-80196D01*
G01X-208792Y-81796D02*
Y-69796D01*
G01X-196792D02*
Y-81796D01*
G01X-198192Y-73796D02*
X-195392D01*
G01X-192192Y-81796D02*
Y-73796D01*
G01Y-75396D02*
X-191692Y-74596D01*
X-191192Y-73996D01*
X-190492Y-73796D01*
X-189992Y-73996D01*
X-189392Y-74596D01*
G01X-182992Y-81796D02*
Y-73796D01*
G01Y-75196D02*
X-183392Y-74396D01*
X-183992Y-73996D01*
X-184692Y-73796D01*
X-185392Y-74196D01*
X-185992Y-74996D01*
X-186392Y-76196D01*
X-186592Y-77796D01*
X-186392Y-79396D01*
X-185992Y-80596D01*
X-185392Y-81396D01*
X-184692Y-81796D01*
X-183992Y-81596D01*
X-183392Y-80996D01*
X-182992Y-80196D01*
G01X-177192Y-74796D02*
X-177892Y-73996D01*
X-178492Y-73796D01*
X-179292Y-74196D01*
X-179892Y-74996D01*
X-180292Y-76396D01*
X-180392Y-77796D01*
X-180292Y-79196D01*
X-179892Y-80396D01*
X-179292Y-81396D01*
X-178492Y-81796D01*
X-177792Y-81396D01*
X-177192Y-80596D01*
G01X-174292Y-76396D02*
X-171092D01*
X-171392Y-74996D01*
X-171892Y-74196D01*
X-172592Y-73796D01*
X-173292Y-73996D01*
X-173892Y-74596D01*
X-174292Y-75996D01*
X-174492Y-77196D01*
Y-78396D01*
X-174292Y-79596D01*
X-173792Y-80796D01*
X-173192Y-81596D01*
X-172492Y-81796D01*
X-171792Y-81396D01*
X-171092Y-80196D01*
G01X-168292Y-80396D02*
X-167792Y-81196D01*
X-167092Y-81796D01*
X-166492D01*
X-165892Y-81396D01*
X-165492Y-80796D01*
X-165292Y-79996D01*
X-165392Y-78796D01*
X-165792Y-78196D01*
X-167592Y-76996D01*
X-167992Y-75596D01*
X-167792Y-74596D01*
X-167392Y-73996D01*
X-166792Y-73796D01*
X-166192Y-73996D01*
X-165592Y-74596D01*
G01X-154792Y-73796D02*
Y-81796D01*
G01Y-70596D02*
X-154992Y-70396D01*
Y-69996D01*
X-154792Y-69796D01*
X-154592Y-69996D01*
Y-70396D01*
X-154792Y-70596D01*
G01X-150492Y-81796D02*
Y-73796D01*
G01Y-75796D02*
X-150092Y-74796D01*
X-149492Y-73996D01*
X-148692Y-73796D01*
X-147992Y-73996D01*
X-147392Y-74796D01*
X-147092Y-76196D01*
Y-81796D01*
G01X-136792D02*
Y-69796D01*
G01X-128992Y-81796D02*
Y-73796D01*
G01Y-75196D02*
X-129392Y-74396D01*
X-129992Y-73996D01*
X-130692Y-73796D01*
X-131392Y-74196D01*
X-131992Y-74996D01*
X-132392Y-76196D01*
X-132592Y-77796D01*
X-132392Y-79396D01*
X-131992Y-80596D01*
X-131392Y-81396D01*
X-130692Y-81796D01*
X-129992Y-81596D01*
X-129392Y-80996D01*
X-128992Y-80196D01*
G01X-126892Y-85396D02*
X-126292Y-85796D01*
X-125492Y-85396D01*
X-124992Y-84596D01*
X-124592Y-83596D01*
X-123992Y-80396D01*
X-122692Y-73796D01*
G01X-125892D02*
X-123992Y-80396D01*
G01X-120292Y-76396D02*
X-117092D01*
X-117392Y-74996D01*
X-117892Y-74196D01*
X-118592Y-73796D01*
X-119292Y-73996D01*
X-119892Y-74596D01*
X-120292Y-75996D01*
X-120492Y-77196D01*
Y-78396D01*
X-120292Y-79596D01*
X-119792Y-80796D01*
X-119192Y-81596D01*
X-118492Y-81796D01*
X-117792Y-81396D01*
X-117092Y-80196D01*
G01X-114192Y-81796D02*
Y-73796D01*
G01Y-75396D02*
X-113692Y-74596D01*
X-113192Y-73996D01*
X-112492Y-73796D01*
X-111992Y-73996D01*
X-111392Y-74596D01*
G01X-99992Y-75396D02*
X-99592Y-74796D01*
X-99292Y-73796D01*
X-99092Y-72396D01*
X-99292Y-71196D01*
X-99692Y-70396D01*
X-100392Y-69796D01*
X-103092D01*
Y-81796D01*
X-99792D01*
X-99092Y-80996D01*
X-98692Y-79796D01*
X-98492Y-78396D01*
X-98692Y-76996D01*
X-99292Y-75796D01*
X-99992Y-75396D01*
X-103092D01*
G01X-94792Y-81796D02*
X-95592Y-81596D01*
X-96292Y-80796D01*
X-96892Y-79596D01*
X-97292Y-78196D01*
X-97492Y-76596D01*
Y-74996D01*
X-97292Y-73396D01*
X-96892Y-71996D01*
X-96292Y-70796D01*
X-95592Y-69996D01*
X-94792Y-69796D01*
X-93992Y-69996D01*
X-93292Y-70796D01*
X-92692Y-71996D01*
X-92292Y-73396D01*
X-92092Y-74996D01*
Y-76596D01*
X-92292Y-78196D01*
X-92692Y-79596D01*
X-93292Y-80796D01*
X-93992Y-81596D01*
X-94792Y-81796D01*
G01X-88792Y-69796D02*
Y-81796D01*
G01X-91092Y-69796D02*
X-86492D01*
G01X-82792D02*
Y-81796D01*
G01X-85092Y-69796D02*
X-80492D01*
G01X-76792Y-81796D02*
X-77592Y-81596D01*
X-78292Y-80796D01*
X-78892Y-79596D01*
X-79292Y-78196D01*
X-79492Y-76596D01*
Y-74996D01*
X-79292Y-73396D01*
X-78892Y-71996D01*
X-78292Y-70796D01*
X-77592Y-69996D01*
X-76792Y-69796D01*
X-75992Y-69996D01*
X-75292Y-70796D01*
X-74692Y-71996D01*
X-74292Y-73396D01*
X-74092Y-74996D01*
Y-76596D01*
X-74292Y-78196D01*
X-74692Y-79596D01*
X-75292Y-80796D01*
X-75992Y-81596D01*
X-76792Y-81796D01*
G01X-73392D02*
Y-69796D01*
X-70792Y-79796D01*
X-68192Y-69796D01*
Y-81796D01*
G01X-522835Y-7874D02*
G03Y0I0J3937D01*
G01X-492126D02*
G03Y-7874I0J-3937D01*
G01X-365355D02*
X-492126D01*
G01Y0D02*
X-522835D01*
G01X-482284Y933071D02*
G03Y925197I0J-3937D01*
G01X-512992D02*
G03Y933071I0J3937D01*
G01Y925197D02*
X-482284D01*
G01Y933071D02*
X-316142D01*
G01X-365355Y-7874D02*
G03Y0I0J3937D01*
G01X-334646D02*
X-365355D01*
G01X-311024Y-7874D02*
G03X-307087Y-3937I0J3937D01*
G01X-334646Y0D02*
G03Y-7874I0J-3937D01*
G01X-311024D02*
X-334646D01*
G01X-318898Y0D02*
G03X-314961Y3937I0J3937D01*
G01X-274410Y31595D02*
G03X-270473Y35532I0J3937D01*
G01X-303150Y31595D02*
G03X-307087Y27658I0J-3937D01*
G01X-318898Y0D02*
G03X-314961Y3937I0J3937D01*
G01X-307087Y27658D02*
Y-3937D01*
G01X-314961Y133859D02*
Y3937D01*
G01Y133859D02*
Y3937D01*
G01X-274410Y31595D02*
X-303150D01*
G01X-311024Y137796D02*
G03X-314961Y133859I0J-3937D01*
G01X-311024Y137796D02*
G03X-314961Y133859I0J-3937D01*
G01X-240158Y137796D02*
X-311024D01*
G01X-240158D02*
X-311024D01*
G01X-285433Y933071D02*
G03Y925197I0J-3937D01*
G01X-316142D02*
G03Y933071I0J3937D01*
G01X-285433D02*
X-224410D01*
G01X-316142Y925197D02*
X-285433D01*
G01X-270473Y125985D02*
Y35532D01*
G01X-266536Y129922D02*
G03X-270473Y125985I0J-3937D01*
G01X-260630Y129922D02*
G03Y137796I0J3937D01*
G01X-244882D02*
G03Y129922I0J-3937D01*
G01X-240158D02*
G03X-228347Y141733I0J11811D01*
G01X-260630Y129922D02*
X-266536D01*
G01X-240158D02*
X-244882D01*
G01X-240158Y137796D02*
G03X-236221Y141733I0J3937D01*
G01X-240158Y137796D02*
G03X-236221Y141733I0J3937D01*
G01X-228347Y368701D02*
Y141733D01*
G01X-236221Y413386D02*
Y141733D01*
G01X-244882Y137796D02*
X-260630D01*
G01X-204725Y409449D02*
G03X-208662Y405512I0J-3937D01*
G01X-232284Y417323D02*
G03X-236221Y413386I0J-3937D01*
G01X-232284Y417323D02*
G03X-236221Y413386I0J-3937D01*
G01X-212599Y372638D02*
G03X-208662Y376575I0J3937D01*
G01X-224410Y372638D02*
G03X-228347Y368701I0J-3937D01*
G01X-181103Y409449D02*
X-204725D01*
G01X-212599Y372638D02*
X-224410D01*
G01X-208662Y405512D02*
Y376575D01*
G01X-232284Y417323D02*
X-181103D01*
G01X-232284D02*
X-181103D01*
G01X-236221Y716536D02*
G03X-232284Y712599I3937J0D01*
G01X-224410Y724410D02*
G03X-220473Y720473I3937J0D01*
G01X-236221Y716536D02*
G03X-232284Y712599I3937J0D01*
G01X-220473Y720473D02*
X-96418D01*
G01Y712599D02*
X-232284D01*
G01X-96418D02*
X-232284D01*
G01X-224410Y933071D02*
Y724410D01*
G01X-236221Y921260D02*
Y716536D01*
G01Y921260D02*
G03X-240158Y925197I-3937J0D01*
G01X-236221Y921260D02*
G03X-240158Y925197I-3937J0D01*
G01X759843Y733661D02*
G02X763780Y737598I3937J0D01*
G01X789764D01*
Y781693D01*
X765945D01*
G02Y789173I0J3740D01*
G01X789764D01*
Y817520D01*
X763780D01*
G02X759843Y821457I0J3937D01*
G01Y921260D01*
G03X755906Y925197I-3937J0D01*
G01X82677D01*
G03X78740Y921260I0J-3937D01*
G01Y791339D01*
G02X74803Y787402I-3937J0D01*
G01X3937D01*
G03X0Y783465I0J-3937D01*
G01Y511811D01*
G02X-3937Y507874I-3937J0D01*
G01X-55118D01*
G03X-59055Y503937I0J-3937D01*
G01Y346457D01*
G02X-62992Y342520I-3937J0D01*
G01X-139803D01*
G03X-143740Y338583I0J-3937D01*
G01Y216535D01*
G03X-139803Y212598I3937J0D01*
G01X-3937D01*
G02X0Y208661I0J-3937D01*
G01Y3937D01*
G03X3937Y0I3937J0D01*
G01X755906D01*
G03X759843Y3937I0J3937D01*
G01Y324213D01*
G02X763780Y328150I3937J0D01*
G01X789764D01*
Y372244D01*
X765945D01*
G02Y379724I0J3740D01*
G01X789764D01*
Y660039D01*
X763780D01*
G02X759843Y663976I0J3937D01*
G01Y733661D01*
G01X-143740Y216536D02*
G03X-139803Y212599I3937J0D01*
G01X-143740Y262205D02*
G03X-151614I-3937J0D01*
G01X-143740Y216536D02*
G03X-139803Y212599I3937J0D01*
G01X-151614Y216536D02*
G03X-139803Y204725I11811J0D01*
G01X-143740Y262205D02*
Y292914D01*
G01Y338583D02*
Y216536D01*
G01Y338583D02*
Y216536D01*
G01X-151614D02*
Y262205D01*
G01X-139803Y212599D02*
X-3937D01*
G01X-139803D02*
X-3937D01*
G01X-15748Y204725D02*
X-139803D01*
G01Y342520D02*
G03X-143740Y338583I0J-3937D01*
G01X-139803Y342520D02*
G03X-143740Y338583I0J-3937D01*
G01X-139803Y350394D02*
G03X-151614Y338583I0J-11811D01*
G01Y292914D02*
G03X-143740I3937J0D01*
G01X-151614D02*
Y338583D01*
G01X-62992Y342520D02*
X-139803D01*
G01X-62992D02*
X-139803D01*
G01X-181103Y409449D02*
G03X-169292Y421260I0J11811D01*
G01X-139803Y350394D02*
X-70866D01*
G01X-177166Y467717D02*
G03X-169292I3937J0D01*
G01X-181103Y417323D02*
G03X-177166Y421260I0J3937D01*
G01X-169292Y437008D02*
G03X-177166I-3937J0D01*
G01X-181103Y417323D02*
G03X-177166Y421260I0J3937D01*
G01X-169292Y437008D02*
Y421260D01*
G01Y570866D02*
Y467717D01*
G01X-177166Y421260D02*
Y578740D01*
G01Y421260D02*
Y578740D01*
G01Y467717D02*
Y437008D01*
G01X-173229Y582677D02*
G03X-177166Y578740I0J-3937D01*
G01X-165355Y574803D02*
G03X-169292Y570866I0J-3937D01*
G01X-173229Y582677D02*
G03X-177166Y578740I0J-3937D01*
G01X-173229Y582677D02*
X-96418D01*
G01X-173229D02*
X-96418D01*
G01Y574803D02*
X-165355D01*
G01X-62992Y342520D02*
G03X-59055Y346457I0J3937D01*
G01X-62992Y342520D02*
G03X-59055Y346457I0J3937D01*
G01X-70866Y350394D02*
G03X-66929Y354331I0J3937D01*
G01D02*
Y457481D01*
G01Y488189D02*
G03X-59055I3937J0D01*
G01Y457481D02*
G03X-66929I-3937J0D01*
G01X-55118Y515748D02*
G03X-66929Y503937I0J-11811D01*
G01Y488189D02*
Y503937D01*
G01X-96418Y582677D02*
G03X-92481Y586615I0J3937D01*
G01X-96418Y582677D02*
G03X-92481Y586615I0J3937D01*
G01X-96418Y574803D02*
G03X-84607Y586615I0J11811D01*
G01Y632284D02*
Y586615D01*
G01X-92481D02*
Y708662D01*
G01Y586615D02*
Y708662D01*
G01Y662992D02*
G03X-84607I3937J0D01*
G01Y632284D02*
G03X-92481I-3937J0D01*
G01X-84607Y708662D02*
Y662992D01*
G01X-92481D02*
Y632284D01*
G01Y708662D02*
G03X-96418Y712599I-3937J0D01*
G01X-92481Y708662D02*
G03X-96418Y712599I-3937J0D01*
G01X-84607Y708662D02*
G03X-96418Y720473I-11811J0D01*
G01X-11811Y-3937D02*
G03X-7874Y-7874I3937J0D01*
G01X31496D02*
X-7874D01*
G01X0Y3937D02*
G03X3937Y0I3937J0D01*
G01X0Y3937D02*
G03X3937Y0I3937J0D01*
G01X0Y3937D02*
Y208662D01*
G01X-11811Y-3937D02*
Y200788D01*
G01X755905Y0D02*
X3937D01*
G01X755905D02*
X3937D01*
G01X-11811Y200788D02*
G03X-15748Y204725I-3937J0D01*
G01X0Y208662D02*
G03X-3937Y212599I-3937J0D01*
G01X0Y208662D02*
G03X-3937Y212599I-3937J0D01*
G01X-59055Y503937D02*
Y346457D01*
G01Y503937D02*
Y346457D01*
G01Y488189D02*
Y457481D01*
G01X-23622Y552559D02*
G03X-27559Y548622I0J-3937D01*
G01X-11811Y552559D02*
G03X-7874Y556496I0J3937D01*
G01X-3937Y507874D02*
G03X0Y511811I0J3937D01*
G01X-3937Y507874D02*
G03X0Y511811I0J3937D01*
G01X-55118Y507874D02*
G03X-59055Y503937I0J-3937D01*
G01X-31496Y515748D02*
G03X-27559Y519685I0J3937D01*
G01X-55118Y507874D02*
G03X-59055Y503937I0J-3937D01*
G01X-23622Y552559D02*
X-11811D01*
G01X0Y511811D02*
Y783465D01*
G01X-27559Y519685D02*
Y548622D01*
G01X-55118Y515748D02*
X-31496D01*
G01X-3937Y507874D02*
X-55118D01*
G01X-3937D02*
X-55118D01*
G01X-7874Y556496D02*
Y783465D01*
G01X3937Y787402D02*
G03X0Y783465I0J-3937D01*
G01X3937Y787402D02*
G03X0Y783465I0J-3937D01*
G01X3937Y795276D02*
G03X-7874Y783465I0J-11811D01*
G01X3937Y795276D02*
X8661D01*
G01X3937Y787402D02*
X74803D01*
G01X3937D02*
X74803D01*
G01X62204Y0D02*
G03Y-7874I0J-3937D01*
G01X31496D02*
G03Y0I0J3937D01*
G01X267716Y-7874D02*
X62204D01*
G01Y0D02*
X31496D01*
G01X74803Y787402D02*
G03X78740Y791339I0J3937D01*
G01X30315Y795276D02*
G03X34252Y799213I0J3937D01*
G01X24409Y795276D02*
G03Y787402I0J-3937D01*
G01X8661D02*
G03Y795276I0J3937D01*
G01X74803Y787402D02*
G03X78740Y791339I0J3937D01*
G01X24409Y795276D02*
X30315D01*
G01X24409Y787402D02*
X8661D01*
G01X34252Y799213D02*
Y889666D01*
G01X38189Y893603D02*
G03X34252Y889666I0J-3937D01*
G01X66929Y893603D02*
G03X70866Y897540I0J3937D01*
G01X38189Y893603D02*
X66929D01*
G01X70866Y897540D02*
Y929134D01*
G01X74803Y933071D02*
G03X70866Y929134I0J-3937D01*
G01X74803Y933071D02*
X88582D01*
G01X78740Y791339D02*
Y921260D01*
G01Y791339D02*
Y921260D01*
G01X119291Y933071D02*
G03Y925197I0J-3937D01*
G01X82677D02*
G03X78740Y921260I0J-3937D01*
G01X88582Y925197D02*
G03Y933071I0J3937D01*
G01X82677Y925197D02*
G03X78740Y921260I0J-3937D01*
G01X119291Y933071D02*
X305118D01*
G01X82677Y925197D02*
X755905D01*
G01X82677D02*
X755905D01*
G01X119291D02*
X88582D01*
G01X267716Y-7874D02*
G03Y0I0J3937D01*
G01X298425D02*
X267716D01*
G01X298425D02*
G03Y-7874I0J-3937D01*
G01X483071D02*
X298425D01*
G01X335827Y933071D02*
G03Y925197I0J-3937D01*
G01X305118D02*
G03Y933071I0J3937D01*
G01X335827D02*
X522441D01*
G01X335827Y925197D02*
X305118D01*
G01X483071Y-7874D02*
G03Y0I0J3937D01*
G01X513779D02*
X483071D01*
G01X513779D02*
G03Y-7874I0J-3937D01*
G01X719291D02*
X513779D01*
G01X553149Y933071D02*
G03Y925197I0J-3937D01*
G01X522441D02*
G03Y933071I0J3937D01*
G01X553149D02*
X719291D01*
G01X553149Y925197D02*
X522441D01*
G01X763779Y-7874D02*
G03X767716Y-3937I0J3937D01*
G01X719291Y-7874D02*
G03Y0I0J3937D01*
G01X750000D02*
G03Y-7874I0J-3937D01*
G01X763779D02*
X750000D01*
G01X755905Y0D02*
G03X759842Y3937I0J3937D01*
G01X755905Y0D02*
G03X759842Y3937I0J3937D01*
G01X767716Y185827D02*
Y-3937D01*
G01X759842Y3937D02*
Y324213D01*
G01X750000Y0D02*
X719291D01*
G01X767716Y185827D02*
G03X759842I-3937J0D01*
G01Y216536D02*
Y185827D01*
G01Y216536D02*
G03X767716I3937J0D01*
G01Y316339D02*
Y216536D01*
G01X771653Y320276D02*
G03X767716Y316339I0J-3937D01*
G01X763779Y328150D02*
G03X759842Y324213I0J-3937D01*
G01X793307Y328150D02*
X763779D01*
G01X791338Y320276D02*
X771653D01*
G01X765945Y379725D02*
G03Y372244I0J-3741D01*
G01X793307Y379725D02*
X765945D01*
G01X793307Y372244D02*
X765945D01*
G01X759842Y663977D02*
G03X763779Y660040I3937J0D01*
G01X759842Y663977D02*
Y733662D01*
G01X793307Y660040D02*
X763779D01*
G01Y737599D02*
G03X759842Y733662I0J-3937D01*
G01X793307Y737599D02*
X763779D01*
G01X765945Y789174D02*
G03Y781693I0J-3740D01*
G01X767716Y829331D02*
G03X771653Y825394I3937J0D01*
G01X759842Y821457D02*
G03X763779Y817520I3937J0D01*
G01X767716Y855118D02*
Y829331D01*
G01X759842Y921260D02*
Y821457D01*
G01X771653Y825394D02*
X791338D01*
G01X793307Y817520D02*
X763779D01*
G01X793307Y789174D02*
X765945D01*
G01X793307Y781693D02*
X765945D01*
G01X767716Y855118D02*
G03X759842I-3937J0D01*
G01Y885827D02*
G03X767716I3937J0D01*
G01Y929134D02*
Y885827D01*
G01X759842D02*
Y855118D01*
G01Y921260D02*
G03X755905Y925197I-3937J0D01*
G01X767716Y929134D02*
G03X763779Y933071I-3937J0D01*
G01X750000D02*
G03Y925197I0J-3937D01*
G01X719291D02*
G03Y933071I0J3937D01*
G01X759842Y921260D02*
G03X755905Y925197I-3937J0D01*
G01X750000Y933071D02*
X763779D01*
G01X750000Y925197D02*
X719291D01*
G01X791338Y-35433D02*
G03X795275Y-31496I0J3937D01*
G01D02*
Y316339D01*
G01D02*
G03X791338Y320276I-3937J0D01*
G01X795275Y370276D02*
Y330118D01*
G01D02*
X793307Y328150D01*
G01X795275Y658071D02*
Y381693D01*
G01D02*
X793307Y379725D01*
G01X795275Y370276D02*
X793307Y372244D01*
G01X795275Y658071D02*
X793307Y660040D01*
G01X795275Y779725D02*
Y739567D01*
G01D02*
X793307Y737599D01*
G01X791338Y825394D02*
G03X795275Y829331I0J3937D01*
G01D02*
Y956693D01*
G01Y815552D02*
Y791142D01*
G01Y815552D02*
X793307Y817520D01*
G01X795275Y779725D02*
X793307Y781693D01*
G01X795275Y791142D02*
X793307Y789174D01*
G01X795275Y956693D02*
G03X791338Y960630I-3937J0D01*
M02*
